G04 ================== begin FILE IDENTIFICATION RECORD ==================*
G04 Layout Name:  9049_F0T_FAN_BOARD_MP5048_D_v02_20221209_0830.brd*
G04 Film Name:    bot.art*
G04 File Format:  Gerber RS274X*
G04 File Origin:  Cadence Allegro 17.2-S081*
G04 Origin Date:  Mon Dec 12 15:05:04 2022*
G04 *
G04 Layer:  DRAWING FORMAT/TITLE_BLOCK_A*
G04 Layer:  PIN/SPECIAL_DRILL*
G04 Layer:  DRAWING FORMAT/TITLE_BLOCK*
G04 Layer:  VIA CLASS/BOTTOM*
G04 Layer:  PIN/BOTTOM*
G04 Layer:  MANUFACTURING/PHOTOPLOT_OUTLINE*
G04 Layer:  ETCH/BOTTOM*
G04 Layer:  DRAWING FORMAT/TITLE_DATA_BOT*
G04 *
G04 Offset:    (0.00 0.00)*
G04 Mirror:    No*
G04 Mode:      Positive*
G04 Rotation:  0*
G04 FullContactRelief:  No*
G04 UndefLineWidth:     6.00*
G04 ================== end FILE IDENTIFICATION RECORD ====================*
%FSLAX25Y25*MOIN*%
%IR0*IPPOS*OFA0.00000B0.00000*MIA0B0*SFA1.00000B1.00000*%
%AMMACRO26*
4,1,6,.01378,.01772,
.0059,.01772,
.0059,-.00984,
-.01378,-.00984,
-.01378,-.01772,
.01378,-.01772,
.01378,.01772,
0.0*
%
%ADD26MACRO26*%
%AMMACRO40*
4,1,46,.05906,.17844,
.059724,.155545,
.06128,.13665,
.09787,-.20608,
.098198,-.223234,
.095542,-.240184,
.089983,-.256415,
.081691,-.271435,
.070916,-.284786,
.057986,-.296063,
.043294,-.304924,
.027287,-.311099,
.010451,-.314401,
-.006703,-.314729,
-.023653,-.312073,
-.039884,-.306514,
-.054904,-.298221,
-.068255,-.287446,
-.079532,-.274517,
-.088393,-.259825,
-.094568,-.243818,
-.09787,-.226982,
-.098198,-.209828,
-.09787,-.20608,
-.06128,.13665,
-.059515,.159487,
-.05906,.17844,
-.05906,.25591,
-.058163,.266166,
-.055498,.27611,
-.051147,.28544,
-.045243,.293873,
-.037963,.301153,
-.02953,.307057,
-.0202,.311408,
-.010256,.314073,
0.0,.31497,
.010256,.314073,
.0202,.311408,
.02953,.307057,
.037963,.301153,
.045243,.293873,
.051147,.28544,
.055498,.27611,
.058163,.266166,
.05906,.25591,
.05906,.17844,
0.0*
%
%ADD40MACRO40*%
%ADD12C,.02*%
%ADD49O,.394X1.26*%
%ADD38R,.13X.095*%
%ADD39R,.13X.099*%
%ADD23R,.007X.036*%
%ADD13C,.026*%
%ADD48R,.032X.197*%
%ADD19R,.099X.13*%
%ADD17C,.054*%
%ADD47C,.039*%
%AMMACRO28*
4,1,5,-.04724,-.00591,
-.04724,0.0,
-.04134,.00591,
.04724,.00591,
.04724,-.00591,
-.04724,-.00591,
0.0*
%
%ADD28MACRO28*%
%ADD11C,.085*%
%ADD16C,.059*%
%ADD18R,.054X.054*%
%AMMACRO35*
4,1,28,-.00748,.00052,
-.00984,.00052,
-.00984,.00603,
-.009782,.006705,
-.009607,.007359,
-.009321,.007974,
-.008933,.008529,
-.008455,.009009,
-.0079,.009398,
-.007286,.009685,
-.006632,.009861,
-.005957,.00992,
-.00591,.00992,
.00591,.00992,
.006585,.009869,
.007242,.009701,
.007859,.009421,
.008418,.009039,
.008903,.008565,
.009297,.008015,
.009591,.007404,
.009773,.006751,
.00984,.006077,
.00984,.00603,
.00984,.00052,
.00748,.00052,
.00748,-.00991,
-.00748,-.00991,
-.00748,.00052,
0.0*
%
%ADD35MACRO35*%
%AMMACRO37*
4,1,28,.00052,.00748,
.00052,.00984,
.00603,.00984,
.006705,.009782,
.007359,.009607,
.007974,.009321,
.008529,.008933,
.009009,.008455,
.009398,.0079,
.009685,.007286,
.009861,.006632,
.00992,.005957,
.00992,.00591,
.00992,-.00591,
.009869,-.006585,
.009701,-.007242,
.009421,-.007859,
.009039,-.008418,
.008565,-.008903,
.008015,-.009297,
.007404,-.009591,
.006751,-.009773,
.006077,-.00984,
.00603,-.00984,
.00052,-.00984,
.00052,-.00748,
-.00991,-.00748,
-.00991,.00748,
.00052,.00748,
0.0*
%
%ADD37MACRO37*%
%AMMACRO34*
4,1,28,-.00748,-.00051,
-.00984,-.00051,
-.00984,-.00602,
-.009782,-.006695,
-.009607,-.007349,
-.009321,-.007964,
-.008933,-.008519,
-.008455,-.008998,
-.0079,-.009388,
-.007287,-.009675,
-.006632,-.009851,
-.005958,-.00991,
-.00591,-.00991,
.00591,-.00991,
.006585,-.009859,
.007242,-.009691,
.007859,-.009411,
.008418,-.009029,
.008903,-.008555,
.009297,-.008005,
.00959,-.007394,
.009773,-.006742,
.00984,-.006068,
.00984,-.00602,
.00984,-.00051,
.00748,-.00051,
.00748,.00992,
-.00748,.00992,
-.00748,-.00051,
0.0*
%
%ADD34MACRO34*%
%AMMACRO36*
4,1,28,-.00051,.00748,
-.00051,.00984,
-.00602,.00984,
-.006695,.009782,
-.007349,.009607,
-.007964,.009321,
-.008519,.008933,
-.008998,.008455,
-.009388,.0079,
-.009675,.007287,
-.009851,.006632,
-.00991,.005958,
-.00991,.00591,
-.00991,-.00591,
-.009859,-.006585,
-.009691,-.007242,
-.009411,-.007859,
-.009029,-.008418,
-.008555,-.008903,
-.008005,-.009297,
-.007394,-.00959,
-.006742,-.009773,
-.006068,-.00984,
-.00602,-.00984,
-.00051,-.00984,
-.00051,-.00748,
.00992,-.00748,
.00992,.00748,
-.00051,.00748,
0.0*
%
%ADD36MACRO36*%
%AMMACRO22*
4,1,6,.01378,-.01772,
.0059,-.01772,
.0059,.00984,
-.01378,.00984,
-.01378,.01772,
.01378,.01772,
.01378,-.01772,
0.0*
%
%ADD22MACRO22*%
%AMMACRO24*
4,1,6,-.01378,-.01772,
-.0059,-.01772,
-.0059,.00984,
.01378,.00984,
.01378,.01772,
-.01378,.01772,
-.01378,-.01772,
0.0*
%
%ADD24MACRO24*%
%ADD43R,.05X.04*%
%ADD21R,.04X.05*%
%ADD45R,.02X.018*%
%ADD46R,.018X.02*%
%ADD31R,.024X.024*%
%ADD30R,.016X.024*%
%ADD29R,.046X.013*%
%ADD42R,.032X.028*%
%ADD51R,.028X.032*%
%ADD10C,.125*%
%ADD20R,.046X.062*%
%ADD50R,.173X.248*%
%AMMACRO44*
4,1,5,.04724,.00591,
.04724,0.0,
.04134,-.00591,
-.04724,-.00591,
-.04724,.00591,
.04724,.00591,
0.0*
%
%ADD44MACRO44*%
%ADD27R,.099X.012*%
%ADD41O,.355X.827*%
%AMMACRO33*
4,1,28,-.00052,-.00748,
-.00052,-.00984,
-.00603,-.00984,
-.006705,-.009782,
-.007359,-.009607,
-.007974,-.009321,
-.008529,-.008933,
-.009009,-.008455,
-.009398,-.0079,
-.009685,-.007286,
-.009861,-.006632,
-.00992,-.005957,
-.00992,-.00591,
-.00992,.00591,
-.009869,.006585,
-.009701,.007242,
-.009421,.007859,
-.009039,.008418,
-.008565,.008903,
-.008015,.009297,
-.007404,.009591,
-.006751,.009773,
-.006077,.00984,
-.00603,.00984,
-.00052,.00984,
-.00052,.00748,
.00991,.00748,
.00991,-.00748,
-.00052,-.00748,
0.0*
%
%ADD33MACRO33*%
%AMMACRO15*
4,1,28,.00748,-.00052,
.00984,-.00052,
.00984,-.00603,
.009782,-.006705,
.009607,-.007359,
.009321,-.007974,
.008933,-.008529,
.008455,-.009009,
.0079,-.009398,
.007286,-.009685,
.006632,-.009861,
.005957,-.00992,
.00591,-.00992,
-.00591,-.00992,
-.006585,-.009869,
-.007242,-.009701,
-.007859,-.009421,
-.008418,-.009039,
-.008903,-.008565,
-.009297,-.008015,
-.009591,-.007404,
-.009773,-.006751,
-.00984,-.006077,
-.00984,-.00603,
-.00984,-.00052,
-.00748,-.00052,
-.00748,.00991,
.00748,.00991,
.00748,-.00052,
0.0*
%
%ADD15MACRO15*%
%AMMACRO32*
4,1,28,.00051,-.00748,
.00051,-.00984,
.00602,-.00984,
.006695,-.009782,
.007349,-.009607,
.007964,-.009321,
.008519,-.008933,
.008998,-.008455,
.009388,-.0079,
.009675,-.007287,
.009851,-.006632,
.00991,-.005958,
.00991,-.00591,
.00991,.00591,
.009859,.006585,
.009691,.007242,
.009411,.007859,
.009029,.008418,
.008555,.008903,
.008005,.009297,
.007394,.00959,
.006742,.009773,
.006068,.00984,
.00602,.00984,
.00051,.00984,
.00051,.00748,
-.00992,.00748,
-.00992,-.00748,
.00051,-.00748,
0.0*
%
%ADD32MACRO32*%
%AMMACRO14*
4,1,28,.00748,.00051,
.00984,.00051,
.00984,.00602,
.009782,.006695,
.009607,.007349,
.009321,.007964,
.008933,.008519,
.008455,.008998,
.0079,.009388,
.007287,.009675,
.006632,.009851,
.005958,.00991,
.00591,.00991,
-.00591,.00991,
-.006585,.009859,
-.007242,.009691,
-.007859,.009411,
-.008418,.009029,
-.008903,.008555,
-.009297,.008005,
-.00959,.007394,
-.009773,.006742,
-.00984,.006068,
-.00984,.00602,
-.00984,.00051,
-.00748,.00051,
-.00748,-.00992,
.00748,-.00992,
.00748,.00051,
0.0*
%
%ADD14MACRO14*%
%AMMACRO25*
4,1,6,-.01378,.01772,
-.0059,.01772,
-.0059,-.00984,
.01378,-.00984,
.01378,-.01772,
-.01378,-.01772,
-.01378,.01772,
0.0*
%
%ADD25MACRO25*%
%ADD52C,.011*%
%ADD53C,.013*%
%ADD54C,.032*%
%ADD55C,.015*%
%ADD56C,.018*%
%ADD57C,.004*%
%ADD58C,.006*%
%ADD59C,.007*%
%ADD63C,.03004*%
%ADD62C,.03604*%
%ADD61C,.12806*%
%ADD60O,.36502X.83702*%
G75*
%LPD*%
G75*
G36*
G01X15748Y1324772D02*
X187795D01*
G02X201543Y1311024I0J-13748D01*
G01Y15748D01*
G02X187795Y2000I-13748J0D01*
G01X145474D01*
X140740Y6734D01*
Y43307D01*
G03X134000Y50031I-6724J0D01*
G01Y52030D01*
G02X142739Y43307I16J-8723D01*
G01Y7562D01*
X146302Y3999D01*
X187795D01*
G03X199544Y15748I0J11749D01*
G01Y1311024D01*
G03X187795Y1322773I-11749J0D01*
G01X15748D01*
G03X3999Y1311024I0J-11749D01*
G01Y15748D01*
G03X15748Y3999I11749J0D01*
G01X57241D01*
X60804Y7562D01*
Y43307D01*
G02X69500Y52030I8723J0D01*
G01Y50031D01*
G03X62803Y43307I27J-6724D01*
G01Y6734D01*
X58069Y2000D01*
X15748D01*
G02X2000Y15748I0J13748D01*
G01Y1311024D01*
G02X15748Y1324772I13748J0D01*
G37*
G36*
G01X6380Y211580D02*
X18700D01*
X20120D01*
X20351Y211349D01*
Y206406D01*
Y203769D01*
X20520Y203600D01*
Y155920D01*
X18500Y153900D01*
X6700D01*
X6059Y154541D01*
X6030Y154569D01*
X6029Y154571D01*
X6000Y154600D01*
Y211117D01*
G02X6059Y211259I200J0D01*
G01X6380Y211580D01*
G37*
G36*
G01X8343Y348120D02*
X27440D01*
X28230Y347330D01*
Y335654D01*
X27287Y334711D01*
X8173D01*
X7400Y335484D01*
Y347177D01*
G02X7459Y347319I200J0D01*
G01X8201Y348061D01*
G02X8343Y348120I142J-141D01*
G37*
G36*
G01X8780Y938470D02*
X18230D01*
X18462Y938238D01*
Y932788D01*
Y930438D01*
X18650Y930250D01*
Y897149D01*
X21351Y894448D01*
G02X21360Y894437I-150J-132D01*
G02X21400Y894317I-160J-120D01*
G01Y869883D01*
G02X21341Y869741I-200J0D01*
G01X20459Y868859D01*
X20431Y868830D01*
X20357Y868800D01*
X8883D01*
G02X8741Y868859I0J200D01*
G01X7859Y869741D01*
X7830Y869769D01*
X7800Y869843D01*
Y937490D01*
X8780Y938470D01*
G37*
G36*
G01X8540Y1029810D02*
X31010D01*
X32711Y1028109D01*
G02X32784Y1028036I-100J-173D01*
G01X32811Y1028009D01*
Y1010794D01*
G02X32752Y1010652I-200J0D01*
G01X31459Y1009359D01*
G02X31317Y1009300I-142J141D01*
G01X9163D01*
G02X9021Y1009359I0J200D01*
G01X7739Y1010641D01*
G02X7680Y1010783I141J142D01*
G01Y1028018D01*
Y1028019D01*
Y1028950D01*
X8540Y1029810D01*
G37*
G36*
G01X8736Y1076500D02*
X30139D01*
G02X30281Y1076441I0J-200D01*
G01X30961Y1075761D01*
G02X31020Y1075619I-141J-142D01*
G01Y1062586D01*
X30126Y1061692D01*
X8529D01*
X7552Y1062669D01*
Y1075316D01*
G02X7611Y1075458I200J0D01*
G01X8594Y1076441D01*
G02X8736Y1076500I142J-141D01*
G37*
G36*
G01X12177Y234439D02*
X21800D01*
X22077Y234162D01*
Y228829D01*
X22766Y228140D01*
X23200D01*
X34281D01*
X34370D01*
X34750Y227760D01*
Y224330D01*
X37654Y221426D01*
X70074D01*
X71500Y220000D01*
Y152130D01*
X52850Y133480D01*
Y123244D01*
G03X52791Y123102I141J-142D01*
G01Y117097D01*
G02X52731Y116955I-200J1D01*
G03Y104845I5969J-6055D01*
G02X52791Y104703I-140J-143D01*
G01Y87405D01*
G02X52778Y87334I-200J0D01*
G03X52198Y84192I8220J-3142D01*
G01Y84188D01*
G03X52384Y82390I8802J2D01*
G02X52379Y82288I-196J-42D01*
G03X51973Y79693I8096J-2596D01*
G01Y79692D01*
G03X52772Y76093I8503J0D01*
G02X52791Y76008I-181J-85D01*
G01Y70174D01*
G02X52732Y70032I-200J0D01*
G01X51159Y68459D01*
G02X51017Y68400I-142J141D01*
G01X44194D01*
G02X44030Y68486I0J200D01*
G01X43814Y68796D01*
X43802Y68892D01*
X43820Y68939D01*
G03X44454Y72479I-9568J3540D01*
G01Y72480D01*
G03X41084Y80057I-10203J0D01*
G01X41083D01*
G02X41018Y80204I135J148D01*
G01Y80504D01*
G02X41083Y80651I200J-1D01*
G01X41084D01*
G03X44454Y88228I-6833J7577D01*
G01Y88229D01*
G03X43695Y92089I-10202J-1D01*
G02Y92241I185J76D01*
G03X44454Y96102I-9443J3861D01*
G03X43695Y99963I-10202J0D01*
G02Y100115I185J76D01*
G03X44454Y103975I-9443J3861D01*
G01Y103976D01*
G03X34252Y114178I-10202J0D01*
G01X34251D01*
G03X30391Y113419I1J-10202D01*
G02X30239I-76J185D01*
G03X26379Y114178I-3861J-9443D01*
G01X26378D01*
G03X16176Y103976I0J-10202D01*
G01Y103975D01*
G03X16935Y100115I10202J1D01*
G02Y99963I-185J-76D01*
G03X16176Y96103I9443J-3861D01*
G01Y96102D01*
G03X19546Y88525I10203J0D01*
G01X19547D01*
G02X19612Y88377I-135J-148D01*
G01Y88079D01*
G02X19547Y87931I-200J0D01*
G01X19546D01*
G03X16176Y80354I6833J-7577D01*
G01Y80353D01*
G03X16935Y76493I10202J1D01*
G02Y76341I-185J-76D01*
G03X16176Y72480I9443J-3861D01*
G01Y72479D01*
G03X16810Y68939I10202J0D01*
G01X16828Y68892D01*
X16816Y68796D01*
X16600Y68486D01*
G02X16436Y68400I-164J114D01*
G01X13150D01*
G02X13008Y68459I0J200D01*
G01X11559Y69908D01*
G02X11500Y70050I141J142D01*
G01Y70343D01*
X11501Y70346D01*
G03X11507Y70675I-8496J320D01*
G03X11501Y71004I-8502J9D01*
G01X11500Y71007D01*
Y90343D01*
X11501Y90346D01*
G03X11507Y90675I-8496J320D01*
G03X11501Y91004I-8502J9D01*
G01X11500Y91007D01*
Y110343D01*
X11501Y110346D01*
G03X11507Y110675I-8496J320D01*
G03X11501Y111004I-8502J9D01*
G01X11500Y111007D01*
Y130343D01*
X11501Y130346D01*
G03X11507Y130675I-8496J320D01*
G03X11501Y131004I-8502J9D01*
G01X11500Y131007D01*
Y136760D01*
X27600Y152860D01*
Y202050D01*
X24400Y205250D01*
X23351Y206299D01*
Y214879D01*
X23310Y214920D01*
X20160Y218070D01*
X11932D01*
X11753Y218249D01*
Y234193D01*
X11999Y234439D01*
X12177D01*
G37*
G36*
G01X50378Y247771D02*
X71290D01*
X71800Y247261D01*
Y229883D01*
G02X71741Y229741I-200J0D01*
G01X70987Y228987D01*
G02X70845Y228928I-142J141D01*
G01X36732D01*
G02X36590Y228987I0J200D01*
G01X35488Y230089D01*
X24517D01*
X24381Y230225D01*
Y235915D01*
X23908Y236388D01*
X12112D01*
X12019Y236481D01*
Y237391D01*
G02X12184Y237588I200J0D01*
G01X34252D01*
X34288D01*
X34291Y237591D01*
X35309D01*
X36672Y236228D01*
X37763D01*
X43228D01*
X45137D01*
X46500Y237591D01*
X48890D01*
X49668Y238369D01*
Y247061D01*
X50378Y247771D01*
G37*
G36*
G01X14260Y303230D02*
X31030D01*
X32200Y302060D01*
Y285983D01*
G02X32141Y285841I-200J0D01*
G01X31087Y284787D01*
G02X30945Y284728I-142J141D01*
G01X14768D01*
G02X14626Y284787I0J200D01*
G01X13744Y285669D01*
G02X13685Y285811I141J142D01*
G01Y302655D01*
X14260Y303230D01*
G37*
G36*
G01X14149Y326497D02*
X32920D01*
G02X33062Y326438I0J-200D01*
G01X42906Y316594D01*
X43133Y316367D01*
X45071D01*
X54700D01*
X54971Y316096D01*
Y310757D01*
X55660Y310068D01*
X55900D01*
X67175D01*
X67333Y309910D01*
Y309065D01*
G02X67133Y308865I-200J0D01*
G01X45000D01*
X43637Y310228D01*
X33260D01*
X32613Y310875D01*
X14004D01*
X12984Y311895D01*
Y325332D01*
X14149Y326497D01*
G37*
G36*
G01X12320Y463800D02*
X16693D01*
G02X16867Y463672I-13J-200D01*
G03X16935Y463501I9513J3684D01*
G01X16950Y463465D01*
Y463386D01*
X16935Y463349D01*
G03X16176Y459489I9443J-3861D01*
G01Y459488D01*
G03X19546Y451911I10203J0D01*
G01X19578Y451882D01*
X19612Y451805D01*
Y451423D01*
X19578Y451346D01*
X19546Y451317D01*
G03X16176Y443740I6833J-7577D01*
G01Y443739D01*
G03X16935Y439879I10202J1D01*
G01X16950Y439842D01*
Y439764D01*
X16935Y439727D01*
G03X16176Y435866I9443J-3861D01*
G03X16935Y432005I10202J0D01*
G01X16950Y431968D01*
Y431890D01*
X16935Y431853D01*
G03X16176Y427992I9443J-3861D01*
G03X16935Y424131I10202J0D01*
G01X16950Y424094D01*
Y424016D01*
X16935Y423979D01*
G03X16176Y420118I9443J-3861D01*
G03X16549Y417386I10202J1D01*
G02X16546Y417270I-193J-53D01*
G03X16176Y414944I7132J-2327D01*
G01Y409544D01*
G03X23678Y402042I7502J0D01*
G01X26021D01*
G02X26115Y402019I1J-200D01*
G01X26213Y401966D01*
X26248Y401936D01*
X26262Y401916D01*
G03X34397Y401960I4052J2848D01*
G02X34549Y402047I166J-113D01*
G01X34556D01*
G03X44454Y412244I-304J10197D01*
G01Y412245D01*
G03X43695Y416105I-10202J-1D01*
G01X43680Y416142D01*
Y416220D01*
X43695Y416257D01*
G03X44454Y420118I-9443J3861D01*
G03X43695Y423979I-10202J0D01*
G01X43680Y424016D01*
Y424094D01*
X43695Y424131D01*
G03X44454Y427992I-9443J3861D01*
G03X43695Y431853I-10202J0D01*
G01X43680Y431890D01*
Y431968D01*
X43695Y432005D01*
G03X44454Y435865I-9443J3861D01*
G01Y435866D01*
G03X41084Y443443I-10203J0D01*
G01X41052Y443472D01*
X41018Y443549D01*
Y443931D01*
X41052Y444008D01*
X41084Y444037D01*
G03X44454Y451614I-6833J7577D01*
G01Y451615D01*
G03X43695Y455475I-10202J-1D01*
G01X43680Y455512D01*
Y455590D01*
X43695Y455627D01*
G03X44454Y459487I-9443J3861D01*
G01Y459488D01*
G03X44321Y461126I-10202J-4D01*
G01X44793Y461598D01*
X51850D01*
G02X52050Y461398I0J-200D01*
G01Y460574D01*
X52013Y460495D01*
X51980Y460466D01*
G03Y447534I5519J-6466D01*
G02X52050Y447382I-130J-152D01*
G01Y446577D01*
X52026Y446511D01*
X52003Y446484D01*
G03X51981Y435543I6497J-5484D01*
G01X52003Y435516D01*
X52038Y435421D01*
G02X52050Y435352I-188J-68D01*
G01Y430372D01*
X52048Y430359D01*
G03X51973Y429230I8427J-1127D01*
G01Y429226D01*
G03X52048Y428097I8502J-2D01*
G01X52050Y428084D01*
Y425872D01*
X52048Y425859D01*
G03X51973Y424730I8427J-1127D01*
G01Y424726D01*
G03X52048Y423597I8502J-2D01*
G01X52050Y423584D01*
Y393173D01*
X60310Y384913D01*
Y375870D01*
X60100Y375660D01*
X60310Y375450D01*
Y346110D01*
X64510Y341910D01*
Y332515D01*
X67500Y329525D01*
Y312500D01*
Y312200D01*
X67317Y312017D01*
X67017D01*
X57411D01*
X57275Y312153D01*
Y317843D01*
X57193Y317925D01*
X56863Y318255D01*
X56802Y318316D01*
X45071D01*
X45034D01*
X44920Y318430D01*
Y325188D01*
X36910Y333198D01*
Y353026D01*
X34295Y355641D01*
X30959D01*
G03X30817Y355700I-142J-141D01*
G01X11956D01*
G02X11814Y355759I0J200D01*
G01X11559Y356014D01*
X11530Y356042D01*
X11500Y356116D01*
Y370324D01*
G03X11507Y370675I-8495J345D01*
G03X11500Y371026I-8502J6D01*
G01Y390324D01*
G03X11507Y390675I-8495J345D01*
G03X11500Y391026I-8502J6D01*
G01Y410324D01*
G03X11507Y410675I-8495J345D01*
G03X11500Y411026I-8502J6D01*
G01Y430324D01*
G03X11507Y430675I-8495J345D01*
G03X11500Y431026I-8502J6D01*
G01Y450324D01*
G03X11507Y450675I-8495J345D01*
G03X11500Y451026I-8502J6D01*
G01Y462980D01*
G02X11557Y463120I200J0D01*
G01X12178Y463741D01*
G02X12180Y463743I142J-140D01*
G02X12320Y463800I140J-143D01*
G37*
G36*
G01X196114Y642752D02*
X192420Y639058D01*
G02X192370Y639022I-140J142D01*
G02X192279Y639000I-91J178D01*
G01X148083D01*
G03X147941Y638941I0J-200D01*
G01X141059Y632059D01*
G03X141000Y631917I141J-142D01*
G01Y558083D01*
G03X141059Y557941I200J0D01*
G01X143943Y555057D01*
G02X143996Y554955I-143J-139D01*
G02X144000Y554917I-196J-40D01*
G01Y554752D01*
G02X143800Y554552I-200J0D01*
G01X139499D01*
G03X138402Y554097I1J-1552D01*
G01X129415Y545110D01*
G02X129274Y545052I-141J142D01*
G01X109000D01*
G03X107448Y543500I0J-1552D01*
G03X108910Y541951I1552J0D01*
G01X108911D01*
X108949Y541949D01*
X109016Y541917D01*
X109034Y541898D01*
G02X109089Y541762I-145J-138D01*
G01Y541692D01*
G02X108898Y541552I-191J60D01*
G01X108499D01*
G03X107402Y541097I1J-1552D01*
G01X106903Y540598D01*
G03X106544Y540038I1097J-1098D01*
G03X106448Y539507I1456J-537D01*
G01Y539500D01*
G03X108000Y537948I1552J0D01*
G03X109060Y538366I0J1553D01*
G01X109087Y538391D01*
X109190Y538433D01*
G02X109265Y538448I76J-185D01*
G01X131451D01*
G03X132548Y538903I-1J1552D01*
G01X141536Y547891D01*
G02X141628Y547942I140J-143D01*
G02X141676Y547948I49J-194D01*
G01X171617D01*
G02X171663Y547943I2J-200D01*
G02X171757Y547891I-46J-195D01*
G01X181942Y537707D01*
G02X181993Y537617I-142J-140D01*
G02X182000Y537566I-193J-52D01*
G01Y532583D01*
G03X182059Y532441I200J0D01*
G01X189966Y524534D01*
G02X190002Y524484I-142J-140D01*
G02X190024Y524393I-178J-91D01*
G01Y524000D01*
G03X190478Y522903I1552J0D01*
G01X192246Y521134D01*
G02X192304Y520993I-142J-141D01*
G01Y520373D01*
G02X192240Y520227I-200J1D01*
G01X192038Y520057D01*
X191998Y520023D01*
G02X191871Y519976I-129J153D01*
G01X191839Y519979D01*
X191830Y519980D01*
G03X191575Y520002I-256J-1480D01*
G03X190449Y519494I0J-1502D01*
G02X190447Y519492I-142J140D01*
G01X190430Y519473D01*
X190353Y519439D01*
X189969Y519440D01*
X189891Y519475D01*
X189863Y519507D01*
G03X188516Y520112I-1347J-1197D01*
G03Y516508I0J-1802D01*
G03X190001Y517289I0J1802D01*
G01X190025Y517324D01*
X190097Y517368D01*
X190435Y517412D01*
G02X190592Y517364I25J-199D01*
G03X191575Y516998I983J1137D01*
G03X191835Y517021I-2J1502D01*
G01X191880Y517029D01*
X191964Y517006D01*
X191972Y517000D01*
X192233Y516780D01*
G02X192239Y516774I-138J-144D01*
G02X192304Y516634I-135J-148D01*
G01Y508388D01*
G02X192245Y508246I-200J0D01*
G01X182902Y498902D01*
X173558Y489558D01*
G02X173478Y489510I-140J143D01*
G02X173417Y489500I-62J190D01*
G01X169083D01*
G03X168941Y489441I0J-200D01*
G01X157312Y477813D01*
G02X157170Y477754I-142J141D01*
G01X117493D01*
G02X117352Y477812I0J200D01*
G01X114917Y480247D01*
G03X113820Y480702I-1098J-1097D01*
G01X111882D01*
G02X111741Y480760I0J200D01*
G01X109736Y482764D01*
G02X109679Y482936I141J142D01*
G01X109728Y483255D01*
G02X109833Y483402I198J-30D01*
G03X110802Y485000I-833J1598D01*
G03X109000Y486802I-1802J0D01*
G03X107295Y485583I0J-1802D01*
G02X107141Y485451I-189J65D01*
G01X107117Y485447D01*
X107024Y485476D01*
X107000Y485500D01*
X83583D01*
G03X83441Y485441I0J-200D01*
G01X76959Y478960D01*
G02X76818Y478902I-141J142D01*
G01X70702D01*
G02X70616Y478922I1J200D01*
G03X68500Y479402I-2116J-4422D01*
G01X63500D01*
G03X60034Y477966I0J-4901D01*
G01X59562Y477494D01*
G03X59534Y477466I3451J-3479D01*
G01X59126Y477058D01*
G02X59076Y477022I-140J142D01*
G02X58985Y477000I-91J178D01*
G01X48395D01*
G02X48357Y477004I2J200D01*
G02X48293Y477028I37J197D01*
G03X47630Y477415I-2795J-4027D01*
G03X45500Y477902I-2130J-4415D01*
G01X15113D01*
G02X15022Y477924I0J200D01*
G02X14972Y477960I90J178D01*
G01X11460Y481472D01*
G02X11424Y481522I142J140D01*
G02X11402Y481613I178J91D01*
G01Y500346D01*
G02X11438Y500459I200J-1D01*
G01X11497Y500545D01*
G02X11583Y500616I165J-113D01*
G01X11584D01*
G03Y503384I-584J1384D01*
G01X11583D01*
G02X11497Y503455I79J184D01*
G01X11438Y503541D01*
G02X11402Y503654I164J114D01*
G01Y504908D01*
G02X11531Y505095I200J0D01*
G03X11532Y507905I-531J1405D01*
G01X11530D01*
X11529Y507906D01*
G02X11437Y507978I72J187D01*
G01X11420Y508004D01*
X11402Y508060D01*
Y509346D01*
G02X11438Y509459I200J-1D01*
G01X11497Y509545D01*
G02X11583Y509616I165J-113D01*
G01X11584D01*
G03Y512384I-584J1384D01*
G01X11583D01*
G02X11497Y512455I79J184D01*
G01X11438Y512541D01*
G02X11402Y512654I164J114D01*
G01Y513908D01*
G02X11531Y514095I200J0D01*
G03X11532Y516905I-531J1405D01*
G01X11530D01*
X11529Y516906D01*
G02X11437Y516978I72J187D01*
G01X11420Y517004D01*
X11402Y517060D01*
Y518408D01*
G02X11531Y518595I200J0D01*
G03X11532Y521405I-531J1405D01*
G01X11530D01*
X11529Y521406D01*
G02X11437Y521478I72J187D01*
G01X11420Y521504D01*
X11402Y521560D01*
Y521769D01*
G02X11437Y521882I200J0D01*
G01X11497Y521968D01*
G02X11581Y522038I165J-113D01*
G01X11582D01*
G03Y524798I-596J1380D01*
G01X11581D01*
G02X11497Y524868I81J183D01*
G01X11437Y524954D01*
G02X11402Y525067I165J113D01*
G01Y638807D01*
G02X11467Y638954I200J-1D01*
G01X11685Y639153D01*
G02X11820Y639206I136J-147D01*
G01X11838Y639205D01*
G03X12000Y639198I159J1795D01*
G03Y642802I0J1802D01*
G03X11838Y642795I-3J-1802D01*
G01X11820Y642794D01*
G02X11685Y642847I1J200D01*
G01X11467Y643046D01*
G02X11402Y643193I135J148D01*
G01Y645249D01*
G02X11480Y645407I200J0D01*
G01X11773Y645605D01*
G02X11803Y645620I104J-171D01*
G01X11949D01*
X11983Y645607D01*
G03X12511Y645511I528J1406D01*
G01X12512D01*
G03Y648515I0J1502D01*
G03X11951Y648406I1J-1502D01*
G01X11950D01*
G02X11776Y648419I-74J186D01*
G01X11480Y648620D01*
G02X11402Y648777I122J158D01*
G01Y651387D01*
G02X11479Y651544I200J-1D01*
G01X11735Y651739D01*
G02X11817Y651776I121J-159D01*
G01X11862Y651785D01*
X11908Y651772D01*
G03X12386Y651707I480J1737D01*
G01X12389D01*
G03Y655311I0J1802D01*
G01X12386D01*
G03X11908Y655246I2J-1802D01*
G01X11862Y655233D01*
X11817Y655242D01*
G02X11735Y655279I39J196D01*
G01X11479Y655474D01*
G02X11402Y655631I123J158D01*
G01Y676912D01*
G02X11483Y677072I200J-1D01*
G01X11516Y677096D01*
X11748Y677264D01*
G02X11834Y677300I118J-162D01*
G01X11881Y677307D01*
X11928Y677291D01*
G03X12500Y677198I571J1709D01*
G01X12519D01*
G03X14302Y679000I-19J1802D01*
G03X12500Y680802I-1802J0D01*
G01X12499D01*
G03X11928Y680709I0J-1802D01*
G02X11832Y680701I-64J189D01*
G01X11787Y680708D01*
X11516Y680904D01*
X11483Y680928D01*
G02X11402Y681088I119J161D01*
G01Y720247D01*
G02X11406Y720285I200J-2D01*
G02X11459Y720387I196J-37D01*
G01X12466Y721394D01*
G03X13902Y724860I-3465J3466D01*
G01Y728409D01*
Y728414D01*
G02X14028Y728595I200J-5D01*
G01X14029D01*
G03X14030Y731953I-654J1679D01*
G01X14028D01*
G02X13936Y732027I74J186D01*
G01X13919Y732051D01*
X13902Y732108D01*
Y743459D01*
G02X13906Y743499I200J0D01*
G01X13918Y743558D01*
X13920Y743562D01*
G02X13925Y743573I185J-77D01*
G02X13986Y743643I177J-93D01*
G01X14249Y743831D01*
G02X14268Y743843I116J-163D01*
G02X14431Y743857I97J-175D01*
G01X14432D01*
G03X15012Y743761I580J1706D01*
G01X15041D01*
G03X16814Y745563I-29J1802D01*
G03X15012Y747365I-1802J0D01*
G01X15011D01*
G03X14445Y747274I-1J-1802D01*
G02X14415Y747266I-66J189D01*
G01X14365Y747258D01*
G02X14340Y747260I3J200D01*
G02X14248Y747295I23J199D01*
G01X13985Y747484D01*
G02X13972Y747494I115J163D01*
G02X13920Y747563I130J152D01*
G01X13915Y747574D01*
G02X13902Y747646I187J71D01*
G01Y750382D01*
G02X13906Y750422I200J0D01*
G02X13950Y750512I196J-40D01*
G01X13951Y750513D01*
G03X13977Y750543I-1122J999D01*
G01X14003Y750569D01*
X14036Y750583D01*
G02X14113Y750598I76J-185D01*
G01X16887D01*
G02X16925Y750594I-2J-200D01*
G02X17027Y750541I-37J-196D01*
G01X18034Y749534D01*
G03X21500Y748098I3466J3465D01*
G01X56270D01*
G03X59736Y749534I0J4901D01*
G01X60593Y750391D01*
G02X60695Y750444I139J-143D01*
G02X60733Y750448I40J-196D01*
G01X74904D01*
G02X75064Y750367I-1J-200D01*
G01X75271Y750089D01*
X75284Y750072D01*
X75297Y750003D01*
X75294Y749956D01*
X75287Y749933D01*
G03X75223Y749500I1438J-434D01*
G03X75720Y748384I1501J0D01*
G01X75737Y748368D01*
X75763Y748332D01*
X75771Y748311D01*
G02X75785Y748222I-186J-75D01*
G01X75775Y748094D01*
X75761Y747905D01*
G02X75733Y747816I-199J14D01*
G01X75711Y747779D01*
X75672Y747753D01*
G03X74998Y746500I828J-1253D01*
G03X78002I1502J0D01*
G03X77505Y747616I-1501J0D01*
G01X77488Y747632D01*
X77462Y747668D01*
X77454Y747689D01*
G02X77440Y747778I186J75D01*
G01X77450Y747906D01*
X77464Y748095D01*
G02X77492Y748184I199J-14D01*
G01X77514Y748221D01*
X77553Y748247D01*
G03X78227Y749500I-828J1253D01*
G03X78163Y749933I-1502J-1D01*
G01X78156Y749956D01*
X78153Y750003D01*
X78166Y750072D01*
X78179Y750089D01*
X78386Y750367D01*
G02X78546Y750448I161J-119D01*
G01X80351D01*
G03X82501Y750945I-1J4902D01*
G01X82521Y750955D01*
X82586Y750971D01*
G02X82633Y750976I45J-195D01*
G01X94785D01*
G03X94927Y751035I0J200D01*
G01X98835Y754943D01*
G02X98937Y754996I139J-143D01*
G02X98975Y755000I40J-196D01*
G01X150755D01*
X150788Y754988D01*
G03X151812I512J1411D01*
G01X151845Y755000D01*
X151917D01*
G03X152059Y755059I0J200D01*
G01X152190Y755190D01*
X152201Y755199D01*
G03X152501Y755499I-901J1201D01*
G01X152510Y755510D01*
X156943Y759943D01*
G02X157045Y759996I139J-143D01*
G02X157083Y760000I40J-196D01*
G01X193077D01*
G02X193115Y759996I-2J-200D01*
G02X193217Y759943I-37J-196D01*
G01X196115Y757045D01*
G02X196168Y756943I-143J-139D01*
G02X196172Y756905I-196J-40D01*
G01Y642893D01*
G02X196150Y642802I-200J0D01*
G02X196114Y642752I-178J90D01*
G37*
G36*
G01X34620Y950390D02*
X35810Y949200D01*
X68900D01*
X70100Y948000D01*
Y860117D01*
X61785Y851802D01*
Y843535D01*
X64592Y840728D01*
X64765D01*
X64817Y840668D01*
X64811Y840511D01*
X63607Y839307D01*
X63517Y839277D01*
X63470Y839284D01*
G03X62216Y839377I-1254J-8408D01*
G03X56056Y836735I0J-8502D01*
G01X56023Y836700D01*
X55930Y836668D01*
X55606Y836717D01*
G02X55519Y836752I29J198D01*
G01X55429Y836817D01*
X55398Y836852D01*
X55387Y836874D01*
G03X47813Y841515I-7574J-3860D01*
G03X41419Y838616I1J-8502D01*
G01X41393Y838587D01*
X41292Y838536D01*
G02X41218Y838516I-88J180D01*
G01X40978Y838497D01*
G02X40966Y838496I-23J199D01*
G02X40833Y838544I-3J200D01*
G03X34252Y840950I-6581J-7797D01*
G01X34251D01*
G03X30391Y840191I1J-10202D01*
G01X30354Y840176D01*
X30276D01*
X30239Y840191D01*
G03X26379Y840950I-3861J-9443D01*
G01X26378D01*
G03X16176Y830748I0J-10202D01*
G01Y830747D01*
G03X16935Y826887I10202J1D01*
G01X16950Y826850D01*
Y826772D01*
X16935Y826735D01*
G03X16176Y822875I9443J-3861D01*
G01Y822874D01*
G03X19546Y815297I10203J0D01*
G01X19578Y815268D01*
X19612Y815191D01*
Y814809D01*
X19578Y814732D01*
X19546Y814703D01*
G03X16176Y807126I6833J-7577D01*
G01Y807125D01*
G03X16935Y803265I10202J1D01*
G01X16950Y803228D01*
Y803150D01*
X16935Y803113D01*
G03X16176Y799252I9443J-3861D01*
G01Y799251D01*
G03X16935Y795390I10202J0D01*
G02X16939Y795379I-186J-74D01*
G02X16938Y795248I-189J-64D01*
G02X16935Y795239I-191J59D01*
G03X16890Y795127I9444J-3859D01*
G02X16704Y795000I-186J73D01*
G01X12171D01*
G02X12029Y795059I0J200D01*
G01X11559Y795529D01*
X11530Y795557D01*
X11500Y795631D01*
Y810324D01*
G03X11507Y810675I-8495J345D01*
G03X11500Y811026I-8502J6D01*
G01Y830324D01*
G03X11507Y830675I-8495J345D01*
G03X11500Y831026I-8502J6D01*
G01Y847371D01*
X28843Y864714D01*
Y866634D01*
G03X28902Y866776I-141J142D01*
G01Y897424D01*
G03X28855Y897553I-200J0D01*
G01X25570Y900838D01*
X25532Y900876D01*
Y928988D01*
X21460Y933060D01*
Y942930D01*
X19090Y945300D01*
X12780D01*
X11991Y946089D01*
Y961111D01*
X12091Y961211D01*
X21989D01*
X22077Y961123D01*
Y958923D01*
Y955523D01*
X22688Y954912D01*
X34288D01*
X34400Y954800D01*
Y950610D01*
X34620Y950390D01*
G37*
G36*
G01X47835Y975898D02*
X69202D01*
X70100Y975000D01*
Y954883D01*
G02X70041Y954741I-200J0D01*
G01X69359Y954059D01*
G02X69217Y954000I-142J141D01*
G01X38432D01*
G02X38290Y954059I0J200D01*
G01X35924Y956424D01*
X35487Y956861D01*
X24539D01*
X24381Y957019D01*
Y962519D01*
X23740Y963160D01*
X12177D01*
X12019Y963318D01*
Y964202D01*
X12177Y964360D01*
X34252D01*
X46746D01*
X46749Y964363D01*
X47418Y965032D01*
Y975481D01*
X47835Y975898D01*
G37*
G36*
G01X13279Y1053364D02*
X31662D01*
G02X31803Y1053306I0J-200D01*
G01X41743Y1043366D01*
X41970Y1043139D01*
X45571D01*
X55300D01*
X55471Y1042968D01*
Y1037529D01*
X55503Y1037497D01*
X56083Y1036917D01*
X56160Y1036840D01*
X67675D01*
X67760D01*
X67800Y1036800D01*
Y1036715D01*
Y1036200D01*
Y1035765D01*
X67675Y1035640D01*
X55560D01*
X55551Y1035649D01*
X46351D01*
X45551D01*
X45532Y1035668D01*
X38132D01*
X36324D01*
X35896Y1036096D01*
X34469Y1037522D01*
X13228D01*
X12519Y1038231D01*
Y1052604D01*
X13279Y1053364D01*
G37*
G36*
G01X43264Y1200119D02*
X47910D01*
G02X48021Y1200085I-1J-200D01*
G01X48130Y1200013D01*
X48166Y1199969D01*
X48178Y1199941D01*
G03X53850Y1195048I7821J3333D01*
G02X53870Y1195042I-47J-194D01*
G02X54000Y1194854I-70J-187D01*
G01Y1188876D01*
G02X53885Y1188695I-200J0D01*
G03X48998Y1181000I3615J-7695D01*
G03X52290Y1174282I8501J0D01*
G01Y1170568D01*
G03X52271Y1170000I8483J-568D01*
G03X52290Y1169432I8502J0D01*
G01Y1169430D01*
G03X52500Y1168040I8483J571D01*
G01Y1159448D01*
G03X51973Y1156501I7975J-2947D01*
G01Y1156500D01*
G03X52262Y1154302I8502J0D01*
G02Y1154198I-193J-52D01*
G03X51973Y1152001I8213J-2198D01*
G01Y1151999D01*
G03X53388Y1147302I8503J0D01*
G01Y1113119D01*
X62700Y1103807D01*
Y1069480D01*
X66649Y1065531D01*
Y1054239D01*
X67244Y1053644D01*
X67714Y1053173D01*
Y1050600D01*
G02X67718Y1050560I-196J-40D01*
G01Y1044618D01*
G02X67714Y1044578I-200J0D01*
G01Y1038828D01*
X67675Y1038789D01*
X57911D01*
X57775Y1038925D01*
Y1044615D01*
X57302Y1045088D01*
X45571D01*
X45492D01*
X45270Y1045310D01*
Y1050447D01*
X38580Y1057137D01*
G02X38522Y1057280I142J141D01*
G01Y1078726D01*
G03X38463Y1078868I-200J0D01*
G01X33388Y1083943D01*
G03X33246Y1084002I-142J-141D01*
G01X11700D01*
G02X11500Y1084202I0J200D01*
G01Y1090324D01*
G03X11507Y1090675I-8495J345D01*
G03X11500Y1091026I-8502J6D01*
G01Y1110324D01*
G03X11507Y1110675I-8495J345D01*
G03X11500Y1111026I-8502J6D01*
G01Y1130324D01*
G03X11507Y1130675I-8495J345D01*
G03X11500Y1131026I-8502J6D01*
G01Y1150324D01*
G03X11507Y1150675I-8495J345D01*
G03X11500Y1151026I-8502J6D01*
G01Y1170324D01*
G03X11507Y1170675I-8495J345D01*
G03X11500Y1171026I-8502J6D01*
G01Y1190324D01*
G03X11507Y1190675I-8495J345D01*
G03X11500Y1191026I-8502J6D01*
G01Y1200090D01*
X11529Y1200119D01*
X17366D01*
G02X17541Y1200016I0J-200D01*
G01X17711Y1199711D01*
G02X17706Y1199508I-175J-97D01*
G03X16176Y1194134I8673J-5374D01*
G01Y1194133D01*
G03X16935Y1190273I10202J1D01*
G01X16950Y1190236D01*
Y1190158D01*
X16935Y1190121D01*
G03X16176Y1186261I9443J-3861D01*
G01Y1186260D01*
G03X19546Y1178683I10203J0D01*
G01X19578Y1178654D01*
X19612Y1178577D01*
Y1178195D01*
X19578Y1178118D01*
X19546Y1178089D01*
G03X16176Y1170512I6833J-7577D01*
G01Y1170511D01*
G03X16935Y1166651I10202J1D01*
G01X16950Y1166614D01*
Y1166536D01*
X16935Y1166499D01*
G03X16176Y1162638I9443J-3861D01*
G03X16935Y1158777I10202J0D01*
G01X16950Y1158740D01*
Y1158662D01*
X16935Y1158625D01*
G03X16176Y1154764I9443J-3861D01*
G03X16935Y1150903I10202J0D01*
G01X16950Y1150866D01*
Y1150788D01*
X16935Y1150751D01*
G03X16176Y1146890I9443J-3861D01*
G03X16549Y1144158I10202J1D01*
G02X16546Y1144042I-193J-53D01*
G03X16176Y1141716I7132J-2327D01*
G01Y1136316D01*
G03X23678Y1128814I7502J0D01*
G01X26021D01*
G02X26115Y1128791I1J-200D01*
G01X26213Y1128738D01*
X26248Y1128708D01*
X26262Y1128688D01*
G03X34397Y1128732I4052J2848D01*
G02X34549Y1128819I166J-113D01*
G01X34556D01*
G03X44454Y1139016I-304J10197D01*
G01Y1139017D01*
G03X43695Y1142877I-10202J-1D01*
G01X43680Y1142914D01*
Y1142992D01*
X43695Y1143029D01*
G03X44454Y1146890I-9443J3861D01*
G03X43695Y1150751I-10202J0D01*
G01X43680Y1150788D01*
Y1150866D01*
X43695Y1150903D01*
G03X44454Y1154764I-9443J3861D01*
G03X44337Y1156303I-10202J-2D01*
G03X49100Y1164000I-3838J7697D01*
G03X42489Y1172367I-8600J0D01*
G03X44454Y1178386I-8238J6020D01*
G01Y1178387D01*
G03X43695Y1182247I-10202J-1D01*
G01X43680Y1182284D01*
Y1182362D01*
X43695Y1182399D01*
G03X44454Y1186260I-9443J3861D01*
G03X43695Y1190121I-10202J0D01*
G01X43680Y1190158D01*
Y1190236D01*
X43695Y1190273D01*
G03X44454Y1194133I-9443J3861D01*
G01Y1194134D01*
G03X42924Y1199508I-10203J0D01*
G02X42919Y1199711I170J106D01*
G01X43089Y1200016D01*
G02X43264Y1200119I175J-97D01*
G37*
G36*
G01X38529Y245728D02*
X43084D01*
G02X43226Y245669I0J-200D01*
G01X43608Y245287D01*
G02X43667Y245145I-141J-142D01*
G01Y239811D01*
G02X43608Y239669I-200J0D01*
G01X43226Y239287D01*
G02X43084Y239228I-142J141D01*
G01X38250D01*
G02X38108Y239287I0J200D01*
G01X37726Y239669D01*
G02X37667Y239811I141J142D01*
G01Y244358D01*
G02X37726Y244499I200J-1D01*
G01X37977Y244751D01*
G03X38405Y245565I-1097J1097D01*
G01X38419Y245637D01*
X38529Y245728D01*
G37*
G36*
G01X48400Y256642D02*
Y273517D01*
G02X48459Y273659I200J0D01*
G01X48741Y273941D01*
G02X48883Y274000I142J-141D01*
G01X64084D01*
G02X64226Y273941I0J-200D01*
G01X65667Y272500D01*
X65775Y272393D01*
G02X65834Y272251I-141J-142D01*
G01Y256642D01*
Y256001D01*
X65114Y255281D01*
X49761D01*
X48821D01*
X48400Y255702D01*
Y256642D01*
G37*
G36*
G01X35744Y306787D02*
X36126Y307169D01*
G02X36268Y307228I142J-141D01*
G01X41102D01*
G02X41244Y307169I0J-200D01*
G01X41626Y306787D01*
G02X41685Y306645I-141J-142D01*
G01Y301311D01*
G02X41626Y301169I-200J0D01*
G01X41244Y300787D01*
G02X41102Y300728I-142J141D01*
G01X36268D01*
G02X36126Y300787I0J200D01*
G01X35744Y301169D01*
G02X35685Y301311I141J142D01*
G01Y306645D01*
G02X35744Y306787I200J0D01*
G37*
G36*
G01X43808Y967741D02*
X43426Y967359D01*
G02X43284Y967300I-142J141D01*
G01X38450D01*
G02X38308Y967359I0J200D01*
G01X37926Y967741D01*
G02X37867Y967883I141J142D01*
G01Y973217D01*
G02X37926Y973359I200J0D01*
G01X38308Y973741D01*
G02X38450Y973800I142J-141D01*
G01X43284D01*
G02X43426Y973741I0J-200D01*
G01X43808Y973359D01*
G02X43867Y973217I-141J-142D01*
G01Y967883D01*
G02X43808Y967741I-200J0D01*
G37*
G36*
G01X47683Y997900D02*
X66367D01*
X66384Y997884D01*
X71533D01*
G02X71675Y997825I0J-200D01*
G01X72141Y997359D01*
G02X72200Y997217I-141J-142D01*
G01Y983574D01*
G02X72124Y983416I-200J-1D01*
G01X71841Y983193D01*
X71751Y983174D01*
X71706Y983185D01*
G03X69900Y983400I-1807J-7487D01*
G01X47400D01*
G02X47200Y983600I0J200D01*
G01Y997417D01*
G02X47259Y997559I200J0D01*
G01X47541Y997841D01*
G02X47683Y997900I142J-141D01*
G37*
G36*
G01X36114Y1032227D02*
X36496Y1032609D01*
G02X36638Y1032668I142J-141D01*
G01X41472D01*
G02X41614Y1032609I0J-200D01*
G01X41996Y1032227D01*
G02X42055Y1032085I-141J-142D01*
G01Y1026751D01*
G02X41996Y1026609I-200J0D01*
G01X41614Y1026227D01*
G02X41472Y1026168I-142J141D01*
G01X36638D01*
G02X36496Y1026227I0J200D01*
G01X36114Y1026609D01*
G02X36055Y1026751I141J142D01*
G01Y1032085D01*
G02X36114Y1032227I200J0D01*
G37*
G36*
G01X71278Y376228D02*
X88317D01*
G02X88459Y376169I0J-200D01*
G01X89841Y374787D01*
G02X89900Y374645I-141J-142D01*
G01Y337083D01*
G02X89841Y336941I-200J0D01*
G01X88959Y336059D01*
G02X88817Y336000I-142J141D01*
G01X68000D01*
X67500Y336500D01*
Y344590D01*
X67290Y344800D01*
Y372240D01*
X71278Y376228D01*
G37*
G36*
G01X71461Y1098861D02*
X91725D01*
G02X91867Y1098802I0J-200D01*
G01X93249Y1097420D01*
G02X93308Y1097278I-141J-142D01*
G01Y1058200D01*
G02X93249Y1058058I-200J0D01*
G01X92877Y1057686D01*
G02X92735Y1057627I-142J141D01*
G01X71500D01*
X69649Y1059478D01*
Y1068051D01*
X69574Y1068126D01*
Y1096974D01*
X69610Y1097010D01*
X71461Y1098861D01*
G37*
G36*
G01X110866Y8900D02*
X112366Y7400D01*
X124200D01*
X125422Y8622D01*
Y30800D01*
X125142Y31080D01*
X118820D01*
X117590Y32310D01*
Y51491D01*
Y52410D01*
Y52910D01*
X117000Y53500D01*
X116500D01*
X111000D01*
X110500Y53000D01*
Y50980D01*
Y32300D01*
X110200Y32000D01*
Y9566D01*
X110866Y8900D01*
G37*
G36*
G01X118930Y303180D02*
X141630D01*
X142500Y302310D01*
Y285783D01*
G02X142441Y285641I-200J0D01*
G01X141587Y284787D01*
G02X141445Y284728I-142J141D01*
G01X119655D01*
G02X119513Y284787I0J200D01*
G01X118159Y286141D01*
G02X118100Y286283I141J142D01*
G01Y301897D01*
Y301898D01*
Y302350D01*
X118930Y303180D01*
G37*
G36*
G01X120308Y327527D02*
X137373D01*
X138482Y326418D01*
Y324401D01*
G03X138541Y324259I200J0D01*
G01X142941Y319859D01*
G03X143083Y319800I142J141D01*
G01X149645D01*
G02X149787Y319741I0J-200D01*
G01X153161Y316367D01*
X164100D01*
X164268Y316199D01*
Y310757D01*
X164957Y310068D01*
X176472D01*
X176630Y309910D01*
Y309065D01*
G02X176465Y308868I-200J0D01*
G01X154397D01*
X154306D01*
X153444Y309730D01*
X152946Y310228D01*
X144461D01*
X143570Y311119D01*
X119592D01*
X118800Y311911D01*
Y326019D01*
X120308Y327527D01*
G37*
G36*
G01X114333Y374450D02*
X134260D01*
X134318Y374392D01*
X134319Y374391D01*
X134790Y373920D01*
X134900Y373810D01*
Y343000D01*
X136000Y341900D01*
Y339000D01*
Y336200D01*
X135700Y335900D01*
X113783D01*
G02X113641Y335959I0J200D01*
G01X112859Y336741D01*
X112830Y336769D01*
X112800Y336843D01*
Y372917D01*
G02X112859Y373059I200J0D01*
G01X114191Y374391D01*
G02X114333Y374450I142J-141D01*
G37*
G36*
G01X133474Y1030498D02*
X141219D01*
G02X141360Y1030440I0J-200D01*
G01X142241Y1029559D01*
G02X142300Y1029417I-141J-142D01*
G01Y1012483D01*
G02X142241Y1012341I-200J0D01*
G01X141459Y1011559D01*
G02X141317Y1011500I-142J141D01*
G01X119383D01*
G02X119241Y1011559I0J200D01*
G01X117959Y1012841D01*
G02X117900Y1012983I141J142D01*
G01Y1029417D01*
G02X117959Y1029559I200J0D01*
G01X118840Y1030440D01*
G02X118981Y1030498I141J-142D01*
G01X127091D01*
X127182D01*
X130291D01*
X130382D01*
X133291D01*
X133382D01*
X133474D01*
G37*
G36*
G01X119833Y1057850D02*
X138067D01*
G02X138209Y1057791I0J-200D01*
G01X152634Y1043366D01*
X152861Y1043139D01*
X154368D01*
X164000D01*
X164268Y1042871D01*
Y1037529D01*
X164300Y1037497D01*
X164880Y1036917D01*
X164957Y1036840D01*
X175940D01*
X176472D01*
X176630Y1036682D01*
Y1036000D01*
Y1035798D01*
X176472Y1035640D01*
X166360D01*
X154374D01*
X154365Y1035649D01*
X154014Y1036000D01*
X153028Y1036986D01*
X145500D01*
X144486Y1038000D01*
X119000D01*
X118300Y1038700D01*
Y1056317D01*
G02X118359Y1056459I200J0D01*
G01X119691Y1057791D01*
G02X119833Y1057850I142J-141D01*
G37*
G36*
G01X112583Y1102500D02*
X128000D01*
X128220Y1102280D01*
Y1076490D01*
X133000Y1071710D01*
Y1066450D01*
X132650Y1066100D01*
X113982D01*
G02X113906Y1066115I0J200D01*
G01X113858Y1066135D01*
G03X113782Y1066150I-76J-185D01*
G01X112433D01*
G02X112291Y1066209I0J200D01*
G01X111059Y1067441D01*
X111030Y1067469D01*
X111000Y1067543D01*
Y1100917D01*
G02X111059Y1101059I200J0D01*
G01X112441Y1102441D01*
G02X112583Y1102500I142J-141D01*
G37*
G36*
G01X132369Y234439D02*
X145600D01*
X145768Y234271D01*
Y228829D01*
X146457Y228140D01*
X157972D01*
X158190Y227922D01*
Y220470D01*
G03X161218Y218660I5361J5530D01*
G01X174220D01*
X174400Y218480D01*
Y218400D01*
Y213400D01*
X172500Y211500D01*
Y181510D01*
X172400Y181410D01*
X170440Y179450D01*
Y159578D01*
G03X170487Y159504I188J68D01*
G01X192042Y137949D01*
Y129431D01*
G03X192034Y129059I8494J-369D01*
G03X192042Y128687I8502J-3D01*
G01Y109431D01*
G03X192034Y109059I8494J-369D01*
G03X192042Y108687I8502J-3D01*
G01Y89431D01*
G03X192034Y89059I8494J-369D01*
G03X192042Y88687I8502J-3D01*
G01Y69431D01*
G03X192034Y69059I8494J-369D01*
G03X192042Y68687I8502J-3D01*
G01Y59595D01*
G02X191984Y59453I-200J-1D01*
G01X191302Y58771D01*
G02X191160Y58712I-142J141D01*
G01X187335D01*
G02X187140Y58870I1J200D01*
G03X183997Y64309I-9976J-2137D01*
G01X183996D01*
G02X183931Y64456I135J148D01*
G01Y64756D01*
G02X183996Y64903I200J-1D01*
G01X183997D01*
G03X187367Y72480I-6833J7577D01*
G01Y72481D01*
G03X186608Y76341I-10202J-1D01*
G02Y76493I185J76D01*
G03X187367Y80354I-9443J3861D01*
G03X186608Y84215I-10202J0D01*
G02Y84367I185J76D01*
G03X187367Y88228I-9443J3861D01*
G03X186608Y92089I-10202J0D01*
G02Y92241I185J76D01*
G03X187367Y96102I-9443J3861D01*
G03X186994Y98835I-10202J0D01*
G02X186997Y98950I193J53D01*
G03X187366Y101273I-7132J2324D01*
G01Y106676D01*
G03X179865Y114178I-7502J0D01*
G01X177472D01*
G02X177308Y114265I1J200D01*
G03X169146Y114260I-4079J-2809D01*
G02X168987Y114173I-165J113D01*
G03X159089Y103976I304J-10197D01*
G01Y103975D01*
G03X159848Y100115I10202J1D01*
G02Y99963I-185J-76D01*
G03X159089Y96102I9443J-3861D01*
G03X159848Y92241I10202J0D01*
G02Y92089I-185J-76D01*
G03X159089Y88228I9443J-3861D01*
G03X159848Y84367I10202J0D01*
G02Y84215I-185J-76D01*
G03X159089Y80355I9443J-3861D01*
G01Y80354D01*
G03X162459Y72777I10203J0D01*
G01X162460D01*
G02X162525Y72630I-135J-148D01*
G01Y72330D01*
G02X162460Y72183I-200J1D01*
G01X162459D01*
G03X160595Y69942I6832J-7578D01*
G01X156500D01*
X150728Y75714D01*
G03X150587Y76507I-8727J-1143D01*
G02X150597Y76626I195J44D01*
G03X151229Y79842I-7870J3217D01*
G03X150540Y83194I-8503J-1D01*
G02X150524Y83272I184J78D01*
G01Y90570D01*
G02X150540Y90648I200J0D01*
G03X151229Y94000I-7814J3353D01*
G03X150540Y97352I-8502J-1D01*
G01X150524Y97390D01*
Y99724D01*
X150541Y99762D01*
G03X151302Y103342I-8040J3580D01*
G03X150541Y106921I-8801J-1D01*
G02X150524Y107003I183J81D01*
G01Y114685D01*
G03X150465Y114827I-200J0D01*
G01X150446Y114846D01*
Y133554D01*
X131500Y152500D01*
Y233570D01*
X132369Y234439D01*
G37*
G36*
G01X176514Y244865D02*
X188643D01*
X189529Y243979D01*
Y226993D01*
X188738Y226202D01*
X176197D01*
G03X176056Y226143I1J-200D01*
G01X175771Y225859D01*
G02X175630Y225800I-142J141D01*
G01X163551D01*
G02X163409Y225859I0J200D01*
G01X159179Y230089D01*
X148208D01*
X148072Y230225D01*
Y235915D01*
X147599Y236388D01*
X135868D01*
X135710Y236546D01*
Y237391D01*
G02X135875Y237588I200J0D01*
G01X157943D01*
X158178D01*
X159417Y236349D01*
X173320D01*
X175848Y238877D01*
Y244199D01*
X176514Y244865D01*
G37*
G36*
G01X145041Y306787D02*
X145423Y307169D01*
G02X145565Y307228I142J-141D01*
G01X150399D01*
G02X150541Y307169I0J-200D01*
G01X150923Y306787D01*
G02X150982Y306645I-141J-142D01*
G01Y301311D01*
G02X150923Y301169I-200J0D01*
G01X150541Y300787D01*
G02X150399Y300728I-142J141D01*
G01X145565D01*
G02X145423Y300787I0J200D01*
G01X145041Y301169D01*
G02X144982Y301311I141J142D01*
G01Y306645D01*
G02X145041Y306787I200J0D01*
G37*
G36*
G01X186767Y448168D02*
G02X186956Y448300I188J-68D01*
G01X191057D01*
G02X191199Y448241I0J-200D01*
G01X191983Y447456D01*
G02X192042Y447314I-141J-142D01*
G01Y429431D01*
G03X192034Y429059I8494J-369D01*
G03X192042Y428687I8502J-3D01*
G01Y409431D01*
G03X192034Y409059I8494J-369D01*
G03X192042Y408687I8502J-3D01*
G01Y389431D01*
G03X192034Y389059I8494J-369D01*
G03X192042Y388687I8502J-3D01*
G01Y369431D01*
G03X192034Y369059I8494J-369D01*
G03X192042Y368687I8502J-3D01*
G01Y359745D01*
X191199Y358902D01*
X172876D01*
G03X172734Y358843I0J-200D01*
G01X167223Y353331D01*
G03X167164Y353189I141J-142D01*
G01Y329311D01*
G03X167222Y329170I200J0D01*
G01X171032Y325360D01*
X175170D01*
X176560Y323970D01*
G02X176630Y323900I-102J-172D01*
G01X176658Y323872D01*
Y312128D01*
X176547Y312017D01*
X176472D01*
X166708D01*
X166572Y312153D01*
Y317843D01*
X166099Y318316D01*
X154434D01*
X154284D01*
X154200Y318400D01*
Y324490D01*
X151655Y327035D01*
X143542Y335148D01*
X142880Y335810D01*
X139800D01*
X139690D01*
X139000Y336500D01*
Y341790D01*
X139800Y342590D01*
X141900Y344690D01*
Y377419D01*
X139059Y380260D01*
G02X139000Y380402I141J142D01*
G01Y389309D01*
G02X139075Y389465I200J0D01*
G01X139319Y389661D01*
G02X139486Y389700I125J-156D01*
G01X139487D01*
G03X141327Y389498I1842J8300D01*
G03X149829Y398000I0J8502D01*
G01Y398002D01*
G03X148920Y401826I-8502J-1D01*
G01X148891Y401884D01*
X148911Y402011D01*
X150579Y403679D01*
G03X150638Y403821I-141J142D01*
G01Y409766D01*
G02X150711Y409920I200J0D01*
G03Y423080I-5384J6580D01*
G01X150676Y423109D01*
X150638Y423189D01*
Y424885D01*
X150652Y424920D01*
G03X151229Y427997I-7925J3079D01*
G01Y428000D01*
G03X150652Y431079I-8502J0D01*
G02X150638Y431152I186J73D01*
G01Y447355D01*
G02X150697Y447497I200J0D01*
G01X151441Y448241D01*
G02X151583Y448300I142J-141D01*
G01X159500D01*
G02X159689Y448168I1J-200D01*
G03X159848Y447753I9604J3442D01*
G02Y447601I-185J-76D01*
G03X159089Y443741I9443J-3861D01*
G01Y443740D01*
G03X162459Y436163I10203J0D01*
G01X162460D01*
G02X162525Y436016I-135J-148D01*
G01Y435716D01*
G02X162460Y435569I-200J1D01*
G01X162459D01*
G03X159089Y427992I6833J-7577D01*
G01Y427991D01*
G03X159848Y424131I10202J1D01*
G02Y423979I-185J-76D01*
G03X159089Y420118I9443J-3861D01*
G03X159848Y416257I10202J0D01*
G02Y416105I-185J-76D01*
G03X159089Y412245I9443J-3861D01*
G01Y412244D01*
G03X169291Y402042I10202J0D01*
G01X169292D01*
G03X173152Y402801I-1J10202D01*
G02X173304I76J-185D01*
G03X177164Y402042I3861J9443D01*
G01X177165D01*
G03X187367Y412244I0J10202D01*
G01Y412245D01*
G03X186608Y416105I-10202J-1D01*
G02Y416257I185J76D01*
G03X187367Y420117I-9443J3861D01*
G01Y420118D01*
G03X183997Y427695I-10203J0D01*
G01X183996D01*
G02X183931Y427842I135J148D01*
G01Y428142D01*
G02X183996Y428289I200J-1D01*
G01X183997D01*
G03X187367Y435866I-6833J7577D01*
G01Y435867D01*
G03X186608Y439727I-10202J-1D01*
G02Y439879I185J76D01*
G03X187367Y443740I-9443J3861D01*
G03X186608Y447601I-10202J0D01*
G02Y447753I185J76D01*
G03X186767Y448168I-9445J3857D01*
G37*
G36*
G01X135868Y964360D02*
X145700D01*
X145768Y964292D01*
Y958750D01*
X145830Y958688D01*
X146428Y958090D01*
X146457Y958061D01*
X157972D01*
X158030Y958003D01*
Y950503D01*
X159976Y948557D01*
G03X165424Y946298I5449J5443D01*
G01X172112D01*
X173355Y945055D01*
X174177Y944233D01*
Y939197D01*
X172500Y937520D01*
X171160D01*
X170030Y936390D01*
Y886177D01*
X179463Y876744D01*
X190953D01*
X192042Y875655D01*
Y869427D01*
G03X192034Y869062I8494J-369D01*
G01Y869056D01*
G03X192042Y868691I8502J4D01*
G01Y849427D01*
G03X192034Y849062I8494J-369D01*
G01Y849056D01*
G03X192042Y848691I8502J4D01*
G01Y829427D01*
G03X192034Y829062I8494J-369D01*
G01Y829056D01*
G03X192042Y828691I8502J4D01*
G01Y809427D01*
G03X192034Y809062I8494J-369D01*
G01Y809056D01*
G03X192042Y808691I8502J4D01*
G01Y789427D01*
G03X192034Y789062I8494J-369D01*
G01Y789056D01*
G03X192042Y788691I8502J4D01*
G01Y770393D01*
X192012Y770319D01*
X191983Y770291D01*
X190945Y769252D01*
X190917Y769223D01*
X190843Y769193D01*
X185880D01*
G02X185703Y769300I0J200D01*
G01X185512Y769664D01*
X185519Y769775D01*
X185551Y769821D01*
G03X187367Y775630I-8386J5810D01*
G01Y775631D01*
G03X186608Y779491I-10202J-1D01*
G01X186593Y779528D01*
Y779606D01*
X186608Y779643D01*
G03X187367Y783503I-9443J3861D01*
G01Y783504D01*
G03X183997Y791081I-10203J0D01*
G01X183965Y791110D01*
X183931Y791187D01*
Y791569D01*
X183965Y791646D01*
X183997Y791675D01*
G03X187367Y799252I-6833J7577D01*
G01Y799253D01*
G03X186608Y803113I-10202J-1D01*
G01X186593Y803150D01*
Y803228D01*
X186608Y803265D01*
G03X187367Y807126I-9443J3861D01*
G03X186608Y810987I-10202J0D01*
G01X186593Y811024D01*
Y811102D01*
X186608Y811139D01*
G03X187367Y815000I-9443J3861D01*
G03X186608Y818861I-10202J0D01*
G01X186593Y818898D01*
Y818976D01*
X186608Y819013D01*
G03X187367Y822874I-9443J3861D01*
G03X186994Y825606I-10202J-1D01*
G02X186997Y825721I193J53D01*
G03X187366Y828045I-7132J2324D01*
G01Y833448D01*
G03X179865Y840950I-7502J0D01*
G01X177522D01*
G02X177428Y840973I-1J200D01*
G01X177330Y841026D01*
X177295Y841056D01*
X177281Y841076D01*
G03X169146Y841032I-4052J-2848D01*
G02X168994Y840945I-166J113D01*
G01X168987D01*
G03X159089Y830748I304J-10197D01*
G01Y830747D01*
G03X159848Y826887I10202J1D01*
G01X159863Y826850D01*
Y826772D01*
X159848Y826735D01*
G03X159089Y822874I9443J-3861D01*
G03X159848Y819013I10202J0D01*
G01X159863Y818976D01*
Y818898D01*
X159848Y818861D01*
G03X159089Y815000I9443J-3861D01*
G03X159848Y811139I10202J0D01*
G01X159863Y811102D01*
Y811024D01*
X159848Y810987D01*
G03X159089Y807127I9443J-3861D01*
G01Y807126D01*
G03X162459Y799549I10203J0D01*
G01X162491Y799520D01*
X162525Y799443D01*
Y799061D01*
X162491Y798984D01*
X162459Y798955D01*
G03X159089Y791378I6833J-7577D01*
G01Y791377D01*
G03X159848Y787517I10202J1D01*
G01X159863Y787480D01*
Y787402D01*
X159848Y787365D01*
G03X159089Y783504I9443J-3861D01*
G03X159848Y779643I10202J0D01*
G01X159863Y779606D01*
Y779528D01*
X159848Y779491D01*
G03X159089Y775631I9443J-3861D01*
G01Y775630D01*
G03X160870Y769873I10202J2D01*
G01X160887Y769847D01*
X160905Y769791D01*
Y769639D01*
G02X160882Y769547I-200J1D01*
G01X160753Y769300D01*
G02X160576Y769193I-177J93D01*
G01X155257D01*
G02X155115Y769252I0J200D01*
G01X152304Y772063D01*
X152275Y772091D01*
X152245Y772165D01*
Y831241D01*
G02X152273Y831344I200J1D01*
G01X152287Y831368D01*
X152325Y831404D01*
X152349Y831417D01*
G03X156151Y835665I-4067J7466D01*
G03X155352Y843603I-7871J3217D01*
G01Y843604D01*
G02X155318Y843715I166J111D01*
G01Y844256D01*
X155350Y844330D01*
X155380Y844359D01*
G03X158002Y850500I-5880J6141D01*
G03X157463Y853479I-8502J0D01*
G02X157451Y853571I187J71D01*
G03X157502Y854496I-8451J930D01*
G01Y854500D01*
G03X149000Y863002I-8502J0D01*
G01X148996D01*
G03X147534Y862875I2J-8502D01*
G02X147466I-34J197D01*
G03X146004Y863002I-1464J-8375D01*
G01X146000D01*
G03X139774Y860290I0J-8503D01*
G02X139628Y860226I-147J136D01*
G01X132774D01*
X131000Y862000D01*
Y962990D01*
X132370Y964360D01*
X135868D01*
G37*
G36*
G01X176475Y973300D02*
X190795D01*
X191597Y972498D01*
Y952855D01*
X190614Y951872D01*
X176458D01*
X174530Y953800D01*
X165425D01*
G02X165283Y953859I0J200D01*
G01X159132Y960010D01*
X148208D01*
X148072Y960146D01*
Y965836D01*
X147599Y966309D01*
X135868D01*
X135596Y966581D01*
Y967372D01*
G02X135655Y967514I200J0D01*
G01X135818Y967677D01*
G02X135868Y967714I143J-140D01*
G01Y967509D01*
X157943D01*
X163509D01*
X163618D01*
X163758Y967649D01*
X170740D01*
X170845Y967754D01*
X170846Y967755D01*
X172796Y969704D01*
X176333Y973241D01*
G02X176475Y973300I142J-141D01*
G37*
G36*
G01X145041Y1033559D02*
X145423Y1033941D01*
G02X145565Y1034000I142J-141D01*
G01X150399D01*
G02X150541Y1033941I0J-200D01*
G01X150923Y1033559D01*
G02X150982Y1033417I-141J-142D01*
G01Y1028083D01*
G02X150923Y1027941I-200J0D01*
G01X150541Y1027559D01*
G02X150399Y1027500I-142J141D01*
G01X145565D01*
G02X145423Y1027559I0J200D01*
G01X145041Y1027941D01*
G02X144982Y1028083I141J142D01*
G01Y1033417D01*
G02X145041Y1033559I200J0D01*
G37*
G36*
G01X187067Y1175400D02*
X191842D01*
G02X192042Y1175200I0J-200D01*
G01Y1169427D01*
G03X192034Y1169062I8494J-369D01*
G01Y1169056D01*
G03X192042Y1168691I8502J4D01*
G01Y1149427D01*
G03X192034Y1149062I8494J-369D01*
G01Y1149056D01*
G03X192042Y1148691I8502J4D01*
G01Y1129427D01*
G03X192034Y1129062I8494J-369D01*
G01Y1129056D01*
G03X192042Y1128691I8502J4D01*
G01Y1109427D01*
G03X192034Y1109062I8494J-369D01*
G01Y1109056D01*
G03X192042Y1108691I8502J4D01*
G01Y1089427D01*
G03X192034Y1089062I8494J-369D01*
G01Y1089056D01*
G03X192042Y1088691I8502J4D01*
G01Y1084102D01*
G02X191842Y1083902I-200J0D01*
G01X177782D01*
G03X172334Y1081643I1J-7702D01*
G01X171857Y1081166D01*
G03X169598Y1075718I5443J-5449D01*
G01Y1058162D01*
X176570Y1051190D01*
X176658Y1051102D01*
Y1049560D01*
Y1044700D01*
Y1038948D01*
X176570Y1038860D01*
X176499Y1038789D01*
X176472D01*
X166708D01*
X166572Y1038925D01*
Y1044615D01*
X166099Y1045088D01*
X154368D01*
X154262D01*
X154150Y1045200D01*
X153630Y1045720D01*
Y1052978D01*
X143516Y1063093D01*
G03X140800Y1064850I-5448J-5444D01*
G01X140772Y1064861D01*
X140725Y1064898D01*
X140654Y1065000D01*
X140460D01*
X139980Y1065480D01*
X136600D01*
X136000Y1066080D01*
Y1066300D01*
Y1072780D01*
X135850Y1072930D01*
X135200Y1073580D01*
Y1108900D01*
X135458Y1109158D01*
X135496Y1109173D01*
G03X140327Y1114004I-3321J8152D01*
G01X140342Y1114042D01*
X152111Y1125811D01*
G03X152170Y1125953I-141J142D01*
G01Y1171800D01*
X152470Y1172100D01*
X155100D01*
X155405Y1171795D01*
G03X155400Y1171504I8596J-293D01*
G01Y1171500D01*
G03X162316Y1163066I8601J0D01*
G03X162459Y1162935I6963J7458D01*
G01X162491Y1162906D01*
X162525Y1162829D01*
Y1162447D01*
X162491Y1162370D01*
X162459Y1162341D01*
G03X159089Y1154764I6833J-7577D01*
G01Y1154763D01*
G03X159848Y1150903I10202J1D01*
G01X159863Y1150866D01*
Y1150788D01*
X159848Y1150751D01*
G03X159089Y1146890I9443J-3861D01*
G03X159848Y1143029I10202J0D01*
G01X159863Y1142992D01*
Y1142914D01*
X159848Y1142877D01*
G03X159089Y1139017I9443J-3861D01*
G01Y1139016D01*
G03X169291Y1128814I10202J0D01*
G01X169292D01*
G03X173152Y1129573I-1J10202D01*
G01X173189Y1129588D01*
X173267D01*
X173304Y1129573D01*
G03X177164Y1128814I3861J9443D01*
G01X177165D01*
G03X187367Y1139016I0J10202D01*
G01Y1139017D01*
G03X186608Y1142877I-10202J-1D01*
G01X186593Y1142914D01*
Y1142992D01*
X186608Y1143029D01*
G03X187367Y1146889I-9443J3861D01*
G01Y1146890D01*
G03X183997Y1154467I-10203J0D01*
G01X183965Y1154496D01*
X183931Y1154573D01*
Y1154955D01*
X183965Y1155032D01*
X183997Y1155061D01*
G03X187367Y1162638I-6833J7577D01*
G01Y1162639D01*
G03X186608Y1166499I-10202J-1D01*
G01X186593Y1166536D01*
Y1166614D01*
X186608Y1166651D01*
G03X187367Y1170512I-9443J3861D01*
G03X186608Y1174373I-10202J0D01*
G01X186593Y1174410D01*
Y1174489D01*
X186608Y1174525D01*
G03X186876Y1175261I-9445J3856D01*
G02X187050Y1175399I190J-61D01*
G02X187067Y1175400I20J-199D01*
G37*
G36*
G01X167299Y239669D02*
X166917Y239287D01*
G02X166775Y239228I-142J141D01*
G01X161941D01*
G02X161799Y239287I0J200D01*
G01X161417Y239669D01*
G02X161358Y239811I141J142D01*
G01Y245145D01*
G02X161417Y245287I200J0D01*
G01X161799Y245669D01*
G02X161941Y245728I142J-141D01*
G01X166775D01*
G02X166917Y245669I0J-200D01*
G01X167299Y245287D01*
G02X167358Y245145I-141J-142D01*
G01Y239811D01*
G02X167299Y239669I-200J0D01*
G37*
G36*
G01X169199Y971090D02*
X168817Y970708D01*
G02X168675Y970649I-142J141D01*
G01X163841D01*
G02X163699Y970708I0J200D01*
G01X163317Y971090D01*
G02X163258Y971232I141J142D01*
G01Y976566D01*
G02X163317Y976708I200J0D01*
G01X163699Y977090D01*
G02X163841Y977149I142J-141D01*
G01X168675D01*
G02X168817Y977090I0J-200D01*
G01X169199Y976708D01*
G02X169258Y976566I-141J-142D01*
G01Y971232D01*
G02X169199Y971090I-200J0D01*
G37*
G36*
G01X177590Y218390D02*
X195537D01*
G02X195679Y218331I0J-200D01*
G01X196941Y217069D01*
G02X197000Y216927I-141J-142D01*
G01Y156300D01*
X196942Y156242D01*
X196941Y156241D01*
X196159Y155459D01*
X196131Y155430D01*
X196129Y155429D01*
X196100Y155400D01*
X185200D01*
X185142Y155458D01*
X185141Y155459D01*
X177930Y162670D01*
Y176370D01*
X179400Y177840D01*
Y197800D01*
Y210500D01*
Y211400D01*
X179200Y211600D01*
X178100Y212700D01*
X177400Y213400D01*
Y218200D01*
X177590Y218390D01*
G37*
G36*
G01X171683Y270900D02*
X194817D01*
G02X194959Y270841I0J-200D01*
G01X195641Y270159D01*
G02X195700Y270017I-141J-142D01*
G01Y252883D01*
G02X195641Y252741I-200J0D01*
G01X194659Y251759D01*
G02X194517Y251700I-142J141D01*
G01X192500D01*
G02X192358Y251759I0J200D01*
G01X191809Y252308D01*
G03X191667Y252366I-141J-142D01*
G01X173490D01*
G03X173348Y252308I-1J-200D01*
G01X172799Y251759D01*
G02X172657Y251700I-142J141D01*
G01X172483D01*
G02X172341Y251759I0J200D01*
G01X171059Y253041D01*
G02X171000Y253183I141J142D01*
G01Y270217D01*
G02X171059Y270359I200J0D01*
G01X171541Y270841D01*
G02X171683Y270900I142J-141D01*
G37*
G36*
G01X175669Y349544D02*
X193910D01*
X194900Y348554D01*
Y334983D01*
G02X194841Y334841I-200J0D01*
G01X192659Y332659D01*
G02X192517Y332600I-142J141D01*
G01X177211D01*
X174665Y335146D01*
Y348365D01*
X174666Y348366D01*
Y348541D01*
X175669Y349544D01*
G37*
G36*
G01X178700Y944370D02*
X195487D01*
G02X195628Y944312I0J-200D01*
G01X197541Y942399D01*
G02X197600Y942257I-141J-142D01*
G01Y885683D01*
G02X197541Y885541I-200J0D01*
G01X196609Y884609D01*
G02X196467Y884550I-142J141D01*
G01X183633D01*
G02X183491Y884609I0J200D01*
G01X177040Y891060D01*
X177000Y891100D01*
Y936200D01*
X177177Y936377D01*
Y944100D01*
X177447Y944370D01*
X178700D01*
G37*
G36*
G01X172009Y998309D02*
X172841Y999141D01*
G02X172983Y999200I142J-141D01*
G01X194917D01*
G02X195059Y999141I0J-200D01*
G01X196441Y997759D01*
G02X196500Y997617I-141J-142D01*
G01Y984583D01*
G02X196441Y984441I-200J0D01*
G01X196430Y984430D01*
X196400Y984357D01*
Y982192D01*
G02X196341Y982050I-200J0D01*
G01X195328Y981037D01*
G02X195186Y980978I-142J141D01*
G01X173203D01*
G02X173061Y981037I0J200D01*
G01X171959Y982139D01*
G02X171900Y982281I141J142D01*
G01Y992157D01*
X171930Y992230D01*
X171950Y992250D01*
Y998167D01*
G02X172009Y998309I200J0D01*
G37*
G36*
G01X177783Y1076400D02*
X191642D01*
X192042Y1076000D01*
Y1057500D01*
X191542Y1057000D01*
X182524D01*
X177100Y1062424D01*
Y1075717D01*
G02X177159Y1075859I200J0D01*
G01X177641Y1076341D01*
G02X177783Y1076400I142J-141D01*
G37*
%LPC*%
G75*
G36*
G01X18998Y497500D02*
G02X22002I1502J0D01*
G02X21632Y496513I-1501J0D01*
G01Y496512D01*
X21631D01*
G03X21583Y496382I152J-130D01*
G01Y496118D01*
G03X21631Y495988I200J0D01*
G01X21632Y495987D01*
G02X22002Y495000I-1131J-987D01*
G02X18998I-1502J0D01*
G02X19368Y495987I1501J0D01*
G01Y495988D01*
X19369D01*
G03X19417Y496118I-152J130D01*
G01Y496382D01*
G03X19369Y496512I-200J0D01*
G01X19368Y496513D01*
G02X18998Y497500I1131J987D01*
G37*
G36*
G01X133998Y562501D02*
G02X135500Y564002I1502J-1D01*
G02X137002Y562500I0J-1502D01*
G02X135501Y560998I-1502J0D01*
G01X135499D01*
G02X135414Y561001I10J1502D01*
G01X135412D01*
X135369Y561003D01*
X135291Y560973D01*
X135017Y560700D01*
X134988Y560621D01*
X134990Y560578D01*
G02X134993Y560491I-1499J-95D01*
G01Y560489D01*
G02X133491Y558988I-1502J1D01*
G02X131989Y560490I0J1502D01*
G02X133490Y561992I1502J0D01*
G01X133492D01*
G02X133577Y561989I-10J-1502D01*
G01X133579D01*
X133622Y561987D01*
X133700Y562017D01*
X133974Y562290D01*
X134003Y562369D01*
X134001Y562412D01*
G02X133998Y562499I1499J95D01*
G01Y562501D01*
G37*
G36*
G01X44762Y654618D02*
X40636D01*
G02X39261Y655207I1J1901D01*
G01X39233Y655237D01*
X39157Y655270D01*
X39054D01*
Y655408D01*
G03X39023Y655515I-200J0D01*
G02X38736Y656519I1615J1005D01*
G01Y660096D01*
X38731Y660120D01*
G02X38674Y660582I1844J462D01*
G01Y684502D01*
G02X38960Y685504I1901J-1D01*
G01Y685505D01*
X38961D01*
G03X38990Y685609I-171J104D01*
G01Y685633D01*
X39107Y685750D01*
X39139D01*
X39198Y685812D01*
G02X40575Y686402I1377J-1312D01*
G02X42476Y684500I-1J-1902D01*
G01Y682602D01*
G03X42676Y682402I200J0D01*
G01X42869D01*
G03X43011Y682461I0J200D01*
G01X43895Y683345D01*
G02X45240Y683902I1345J-1345D01*
G02X47142Y682000I0J-1902D01*
G02X46585Y680655I-1902J0D01*
G01X45085Y679155D01*
G02X43740Y678598I-1345J1345D01*
G01X42676D01*
G03X42476Y678398I0J-200D01*
G01Y670602D01*
G03X42676Y670402I200J0D01*
G01X43369D01*
G03X43511Y670461I0J200D01*
G01X43895Y670845D01*
G02X44936Y671377I1344J-1345D01*
G01X44981Y671384D01*
X45053Y671433D01*
X45255Y671774D01*
X45264Y671862D01*
X45249Y671904D01*
G02X45148Y672498I1701J595D01*
G01Y672500D01*
G02X48752I1802J0D01*
G02X47304Y670733I-1802J0D01*
G01X47260Y670724D01*
X47189Y670672D01*
X47021Y670364D01*
G03X47010Y670195I175J-96D01*
G02X47142Y669500I-1770J-696D01*
G02X47010Y668805I-1902J1D01*
G03X47021Y668636I186J-73D01*
G01X47189Y668328D01*
X47260Y668276D01*
X47304Y668267D01*
G02X48752Y666500I-354J-1767D01*
G02X46950Y664698I-1802J0D01*
G02X45159Y666302I0J1802D01*
G01Y666303D01*
G03X45075Y666444I-199J-23D01*
G01X44796Y666641D01*
X44713Y666658D01*
X44671Y666648D01*
G02X44240Y666598I-433J1852D01*
G01X42676D01*
G03X42476Y666398I0J-200D01*
G01Y661005D01*
X42482Y660981D01*
G02X42540Y660519I-1843J-466D01*
G01Y658620D01*
G03X42740Y658420I200J0D01*
G01X43902D01*
G03X44029Y658466I-1J200D01*
G02X45240Y658902I1212J-1466D01*
G02X47142Y657000I0J-1902D01*
G02X46585Y655655I-1902J0D01*
G01X46104Y655174D01*
G02X44762Y654618I-1344J1346D01*
G37*
G36*
G01X179498Y696500D02*
G02X182502I1502J0D01*
G02X181093Y695001I-1502J0D01*
G01X181048Y694998D01*
X180969Y694954D01*
X180762Y694662D01*
G03X180733Y694492I163J-115D01*
G02X180802Y694000I-1733J-494D01*
G02X179000Y695802I-1802J0D01*
G02X179100Y695799I-4J-1802D01*
G01X179101D01*
X179145Y695797D01*
X179229Y695831D01*
X179468Y696096D01*
G03X179517Y696261I-149J134D01*
G01Y696262D01*
G02X179498Y696500I1483J238D01*
G37*
G36*
G01X18525Y711174D02*
G02X22129I1802J0D01*
G02X21465Y709777I-1802J0D01*
G01X21431Y709749D01*
X21393Y709671D01*
X21384Y709278D01*
X21419Y709198D01*
X21452Y709169D01*
G02X21955Y708047I-1000J-1122D01*
G02X18951I-1502J0D01*
G02X19367Y709084I1502J-1D01*
G03X19422Y709243I-144J139D01*
G01X19386Y709590D01*
X19341Y709665D01*
X19305Y709690D01*
G02X18525Y711174I1022J1484D01*
G37*
G36*
G01X72976Y513646D02*
Y496998D01*
G02X71075Y495098I-1901J1D01*
G02X69960Y495460I1J1902D01*
G03X69842Y495498I-117J-162D01*
G01X68315D01*
X68291Y495492D01*
G02X67925Y495448I-367J1508D01*
G01X66651D01*
G03X66509Y495389I0J-200D01*
G01X58022Y486903D01*
G02X56925Y486448I-1098J1097D01*
G02X55374Y488000I1J1552D01*
G02X55828Y489097I1552J0D01*
G01X64828Y498097D01*
G02X65925Y498552I1098J-1097D01*
G01X67925D01*
G02X68291Y498508I-1J-1552D01*
G01X68315Y498502D01*
X68974D01*
G03X69174Y498702I0J200D01*
G01Y499798D01*
G03X68974Y499998I-200J0D01*
G01X68315D01*
X68291Y499992D01*
G02X67925Y499948I-367J1508D01*
G01X66151D01*
G03X66009Y499889I0J-200D01*
G01X58022Y491903D01*
G02X56925Y491448I-1098J1097D01*
G02X55374Y493000I1J1552D01*
G02X55828Y494097I1552J0D01*
G01X64328Y502597D01*
G02X65425Y503052I1098J-1097D01*
G01X67925D01*
G02X68291Y503008I-1J-1552D01*
G01X68315Y503002D01*
X68974D01*
G03X69174Y503202I0J200D01*
G01Y504298D01*
G03X68974Y504498I-200J0D01*
G01X68315D01*
X68291Y504492D01*
G02X67925Y504448I-367J1508D01*
G01X65651D01*
G03X65509Y504389I0J-200D01*
G01X58022Y496903D01*
G02X56925Y496448I-1098J1097D01*
G02X55374Y498000I1J1552D01*
G02X55828Y499097I1552J0D01*
G01X57247Y500516D01*
G03X57289Y500735I-142J141D01*
G01X57120Y501133D01*
X57017Y501199D01*
X56957Y501198D01*
X56925D01*
G02X58727Y503000I0J1802D01*
G01Y502968D01*
X58726Y502908D01*
X58792Y502805D01*
X59190Y502636D01*
G03X59409Y502678I78J184D01*
G01X63828Y507097D01*
G02X64925Y507552I1098J-1097D01*
G01X67925D01*
G02X68291Y507508I-1J-1552D01*
G01X68315Y507502D01*
X68974D01*
G03X69174Y507702I0J200D01*
G01Y508798D01*
G03X68974Y508998I-200J0D01*
G01X68315D01*
X68291Y508992D01*
G02X67925Y508948I-367J1508D01*
G01X59651D01*
G03X59509Y508890I-1J-200D01*
G01X58689Y508070D01*
X58664Y508027D01*
X58657Y508002D01*
G02X56925Y506698I-1732J498D01*
G02X55123Y508500I0J1802D01*
G02X56427Y510232I1802J0D01*
G01X56452Y510239D01*
X56495Y510264D01*
X57828Y511597D01*
G02X58925Y512052I1098J-1097D01*
G01X67925D01*
G02X68291Y512008I-1J-1552D01*
G01X68315Y512002D01*
X68974D01*
G03X69174Y512202I0J200D01*
G01Y513298D01*
G03X68974Y513498I-200J0D01*
G01X68315D01*
X68291Y513492D01*
G02X67925Y513448I-367J1508D01*
G01X60425D01*
G02X59328Y513903I1J1552D01*
G01X56495Y516736D01*
X56452Y516761D01*
X56427Y516768D01*
G02X55123Y518500I498J1732D01*
G02X56925Y520302I1802J0D01*
G02X58657Y518998I0J-1802D01*
G01X58664Y518973D01*
X58689Y518930D01*
X61009Y516611D01*
G03X61151Y516552I142J141D01*
G01X67925D01*
G02X68291Y516508I-1J-1552D01*
G01X68315Y516502D01*
X68974D01*
G03X69174Y516702I0J200D01*
G01Y517798D01*
G03X68974Y517998I-200J0D01*
G01X68315D01*
X68291Y517992D01*
G02X67925Y517948I-367J1508D01*
G01X63621D01*
G02X62524Y518403I1J1552D01*
G01X59037Y521889D01*
G03X58895Y521948I-142J-141D01*
G01X57895D01*
G03X57798Y521923I0J-200D01*
G02X56927Y521698I-872J1577D01*
G01X56925D01*
G02Y525302I0J1802D01*
G01X56927D01*
G02X57798Y525077I-1J-1802D01*
G03X57895Y525052I97J175D01*
G01X59621D01*
G02X60718Y524597I-1J-1552D01*
G01X64205Y521111D01*
G03X64347Y521052I142J141D01*
G01X67925D01*
G02X68291Y521008I-1J-1552D01*
G01X68315Y521002D01*
X68974D01*
G03X69174Y521202I0J200D01*
G01Y522298D01*
G03X68974Y522498I-200J0D01*
G01X68315D01*
X68291Y522492D01*
G02X67925Y522448I-367J1508D01*
G01X65269D01*
G02X64172Y522903I1J1552D01*
G01X60185Y526889D01*
G03X60043Y526948I-142J-141D01*
G01X57895D01*
G03X57798Y526923I0J-200D01*
G02X56927Y526698I-872J1577D01*
G01X56925D01*
G02Y530302I0J1802D01*
G01X56927D01*
G02X57798Y530077I-1J-1802D01*
G03X57895Y530052I97J175D01*
G01X60769D01*
G02X61866Y529597I-1J-1552D01*
G01X65853Y525611D01*
G03X65995Y525552I142J141D01*
G01X67925D01*
G02X68291Y525508I-1J-1552D01*
G01X68315Y525502D01*
X68974D01*
G03X69174Y525702I0J200D01*
G01Y526798D01*
G03X68974Y526998I-200J0D01*
G01X68315D01*
X68291Y526992D01*
G02X67925Y526948I-367J1508D01*
G01X67000D01*
G02X65903Y527403I1J1552D01*
G01X56570Y536736D01*
X56527Y536761D01*
X56502Y536768D01*
G02X55198Y538500I498J1732D01*
G02X57000Y540302I1802J0D01*
G02X58732Y538998I0J-1802D01*
G01X58739Y538973D01*
X58764Y538930D01*
X67584Y530111D01*
G03X67726Y530052I142J141D01*
G01X67925D01*
G02X68291Y530008I-1J-1552D01*
G01X68315Y530002D01*
X69268D01*
G03X69468Y530202I0J200D01*
G01Y531185D01*
G03X69384Y531348I-200J0D01*
G01X69119Y531537D01*
G03X68937Y531563I-116J-163D01*
G02X68345Y531463I-592J1702D01*
G02X66543Y533265I0J1802D01*
G02X67395Y534796I1802J0D01*
G01X67435Y534821D01*
X67483Y534897D01*
X67524Y535255D01*
G03X67466Y535419I-199J22D01*
G01X67155Y535730D01*
G02X66598Y537075I1345J1345D01*
G02X68500Y538976I1902J-1D01*
G01X68503D01*
G02X69845Y538420I-2J-1902D01*
G01X72715Y535550D01*
G02X73272Y534205I-1345J-1345D01*
G01Y528795D01*
G02X73004Y527824I-1901J2D01*
G03X72976Y527721I172J-102D01*
G01Y516514D01*
G03X73093Y516332I200J0D01*
G01X73425Y516181D01*
G03X73639Y516212I83J182D01*
G02X73896Y516393I989J-1131D01*
G01X73898D01*
X73932Y516413D01*
X73980Y516472D01*
X74082Y516817D01*
X74074Y516894D01*
X74056Y516929D01*
G02X73848Y517769I1594J840D01*
G01Y517770D01*
G02X77452I1802J0D01*
G02X76281Y516082I-1802J0D01*
G01X76244Y516069D01*
X76187Y516016D01*
X76035Y515691D01*
X76031Y515613D01*
X76044Y515576D01*
G02X76128Y515081I-1418J-495D01*
G01Y515080D01*
G02X74626Y513578I-1502J0D01*
G02X73639Y513948I0J1501D01*
G01X73594Y513987D01*
X73479Y514003D01*
X73093Y513828D01*
G03X72976Y513646I83J-182D01*
G37*
G36*
G01X159425Y513552D02*
G02X159791Y513508I-1J-1552D01*
G01X159815Y513502D01*
X160474D01*
G03X160674Y513702I0J200D01*
G01Y514798D01*
G03X160474Y514998I-200J0D01*
G01X159815D01*
X159791Y514992D01*
G02X159425Y514948I-367J1508D01*
G02X159059Y514992I1J1552D01*
G01X159035Y514998D01*
X158525D01*
G02X158023Y515500I0J502D01*
G01Y515625D01*
G03X157964Y515767I-200J0D01*
G01X155841Y517889D01*
G03X155699Y517948I-142J-141D01*
G01X150575D01*
G02Y521052I0J1552D01*
G01X156425D01*
G02X156688Y521029I-3J-1552D01*
G01X156736Y521021D01*
X156829Y521050D01*
X156864Y521085D01*
G03Y521367I-142J141D01*
G01X155673Y522558D01*
G02X155400Y522927I1097J1097D01*
G01X155380Y522966D01*
X155310Y523018D01*
X154927Y523104D01*
X154842Y523085D01*
X154807Y523059D01*
G02X153725Y522698I-1082J1441D01*
G02X152276Y523429I0J1802D01*
G01X152250Y523464D01*
X152172Y523507D01*
X151822Y523528D01*
G03X151665Y523467I-13J-199D01*
G01X151664Y523466D01*
G02X150575Y522998I-1089J1033D01*
G02Y526002I0J1502D01*
G02X151664Y525534I0J-1501D01*
G01X151665Y525533D01*
G03X151822Y525472I144J138D01*
G01X152172Y525493D01*
X152250Y525536D01*
X152276Y525571D01*
G02X152941Y526122I1449J-1071D01*
G03X153051Y526269I-87J180D01*
G01X153106Y526590D01*
G03X153050Y526765I-197J33D01*
G01X151925Y527889D01*
G03X151783Y527948I-142J-141D01*
G01X150575D01*
G02Y531052I0J1552D01*
G01X152081D01*
G03X152265Y531175I0J200D01*
G01X152289Y531231D01*
X152265Y531350D01*
X150961Y532654D01*
G03X150795Y532711I-141J-141D01*
G02X150575Y532698I-216J1789D01*
G02X148773Y534500I0J1802D01*
G02X150130Y536246I1802J0D01*
G03X150274Y536387I-49J194D01*
G01X150365Y536722D01*
G03X150314Y536916I-193J53D01*
G01X149478Y537753D01*
G02X149024Y538850I1098J1097D01*
G01Y539502D01*
G02X150575Y541052I1551J-1D01*
G02X152125Y539568I0J-1551D01*
G01X152126Y539531D01*
X152156Y539463D01*
X160058Y531561D01*
G03X160200Y531502I142J141D01*
G01X160474D01*
G03X160674Y531702I0J200D01*
G01Y535653D01*
G02X161230Y536995I1902J-2D01*
G01X167655Y543420D01*
G02X169000Y543976I1344J-1346D01*
G02X170902Y542075I1J-1901D01*
G02X170345Y540730I-1902J0D01*
G01X164535Y534921D01*
G03X164476Y534779I141J-142D01*
G01Y498498D01*
G02X162575Y496598I-1901J1D01*
G02X161460Y496960I1J1902D01*
G03X161342Y496998I-117J-162D01*
G01X160200D01*
G03X160058Y496939I0J-200D01*
G01X151845Y488725D01*
X151832Y488704D01*
G02X150500Y487948I-1332J795D01*
G02X148948Y489500I0J1552D01*
G01Y489575D01*
G02X149403Y490672I1552J-1D01*
G01X151056Y492326D01*
G03X151095Y492554I-141J142D01*
G01X150905Y492952D01*
X150795Y493013D01*
X150732Y493006D01*
G02X150575Y492998I-155J1494D01*
G02X152077Y494500I0J1502D01*
G02X152069Y494343I-1502J-2D01*
G01X152062Y494280D01*
X152123Y494170D01*
X152521Y493980D01*
G03X152749Y494019I86J180D01*
G01X156364Y497633D01*
G03Y497915I-142J141D01*
G01X156329Y497950D01*
X156236Y497979D01*
X156188Y497971D01*
G02X155925Y497948I-266J1529D01*
G01X150575D01*
G02Y501052I0J1552D01*
G01X155199D01*
G03X155341Y501111I0J200D01*
G01X156863Y502633D01*
G03X156864Y502915I-141J142D01*
G01X156829Y502950D01*
X156736Y502979D01*
X156688Y502971D01*
G02X156425Y502948I-266J1529D01*
G01X151545D01*
G03X151448Y502923I0J-200D01*
G02X150577Y502698I-872J1577D01*
G01X150575D01*
G02Y506302I0J1802D01*
G01X150577D01*
G02X151448Y506077I-1J-1802D01*
G03X151545Y506052I97J175D01*
G01X155699D01*
G03X155841Y506111I0J200D01*
G01X157363Y507633D01*
G03X157364Y507915I-141J142D01*
G01X157329Y507950D01*
X157236Y507979D01*
X157188Y507971D01*
G02X156925Y507948I-266J1529D01*
G01X150575D01*
G02Y511052I0J1552D01*
G01X156199D01*
G03X156341Y511111I0J200D01*
G01X157964Y512733D01*
G03X158023Y512875I-141J142D01*
G01Y513000D01*
G02X158525Y513502I502J0D01*
G01X159035D01*
X159059Y513508D01*
G02X159425Y513552I367J-1508D01*
G37*
G36*
G01X77853Y636059D02*
G02X77175Y637315I824J1256D01*
G02X80179I1502J0D01*
G02X79327Y635961I-1502J0D01*
G03X79281Y635266I173J-360D01*
G02X79959Y634010I-824J-1256D01*
G02X76955I-1502J0D01*
G02X77807Y635364I1502J0D01*
G03X77853Y636059I-173J360D01*
G37*
G36*
G01X45938Y648100D02*
G02X45697Y649000I1560J900D01*
G02X47499Y647198I1802J0D01*
G02X47269Y647213I2J1802D01*
G03X46857Y646644I-51J-397D01*
G02X47002Y646000I-1358J-644D01*
G02X45500Y647502I-1502J0D01*
G02X45572Y647500I-6J-1502D01*
G03X45938Y648100I20J400D01*
G37*
G36*
G01X65806Y665035D02*
G02X65475Y664998I-331J1465D01*
G02X66977Y666500I0J1502D01*
G02X66943Y666183I-1502J1D01*
G03X67455Y665718I391J-84D01*
G02X67998Y665802I544J-1718D01*
G01X68000D01*
G02X66198Y664000I0J-1802D01*
G01Y664001D01*
G02X66277Y664528I1802J-1D01*
G03X65806Y665035I-382J117D01*
G37*
G36*
G01Y677535D02*
G02X65475Y677498I-331J1465D01*
G02X66977Y679000I0J1502D01*
G02X66943Y678683I-1502J1D01*
G03X67455Y678218I391J-84D01*
G02X67998Y678302I544J-1718D01*
G01X68000D01*
G02X66198Y676500I0J-1802D01*
G01Y676501D01*
G02X66277Y677028I1802J-1D01*
G03X65806Y677535I-382J117D01*
G37*
G36*
G01X177319Y677707D02*
G02X175698Y679500I181J1793D01*
G02X179302I1802J0D01*
G02X179043Y678569I-1803J0D01*
G03X179304Y677971I342J-206D01*
G02X180502Y676500I-304J-1471D01*
G02X177498I-1502J0D01*
G02X177641Y677139I1502J-1D01*
G03X177319Y677707I-362J170D01*
G37*
G36*
G01X13822Y711051D02*
G02X13428Y710998I-396J1449D01*
G01X13425D01*
G02X14927Y712500I0J1502D01*
G01Y712497D01*
G02X14835Y711981I-1502J2D01*
G03X15316Y711458I375J-138D01*
G02X15710Y711511I396J-1449D01*
G01X15713D01*
G02X14211Y710009I0J-1502D01*
G01Y710012D01*
G02X14303Y710528I1502J-2D01*
G03X13822Y711051I-375J138D01*
G37*
G54D63*
X121536Y749253D03*
X93000Y745000D03*
X118000Y696000D03*
X65475Y685000D03*
X187925Y701000D03*
X106000Y634500D03*
X181475Y740000D03*
X187050Y659500D03*
X184425Y738000D03*
X181475Y720000D03*
X120000Y504500D03*
X74857Y611575D03*
X167075Y756500D03*
X65500Y671500D03*
X135000Y637500D03*
X101284Y671500D03*
X125000Y562500D03*
X85000Y562148D03*
X128000Y504500D03*
X179000Y535075D03*
X128000Y512500D03*
X120000D03*
X175500Y672500D03*
X74075Y721500D03*
X180500Y684500D03*
X33500Y694425D03*
X182500Y688000D03*
X74075Y726500D03*
X26500Y732500D03*
X18000Y491500D03*
X187500Y643500D03*
X28900Y556900D03*
X79975Y739975D03*
X14925Y663000D03*
X91532Y663261D03*
X148000Y483000D03*
X136500Y742000D03*
X187041Y730000D03*
X177000Y522000D03*
X172000Y751500D03*
X78500Y504500D03*
X72500Y541500D03*
X170000Y504500D03*
X86500Y512500D03*
X105815Y488500D03*
X177000Y514000D03*
X78500Y512500D03*
X108500Y512000D03*
X134000Y501000D03*
X86500Y504500D03*
X37500Y520500D03*
X150500Y544500D03*
X169000Y514000D03*
Y522000D03*
X56925Y533500D03*
Y513500D03*
X116000Y529500D03*
X35484Y534075D03*
X49250Y516750D03*
X37500Y512500D03*
X29500D03*
Y520500D03*
X65552Y645503D03*
X57000Y483000D03*
X98925Y512500D03*
Y524000D03*
X66400Y655400D03*
X141500Y516500D03*
X86000Y696000D03*
X75396Y544500D03*
X93000Y731000D03*
X105732Y496844D03*
X102075Y534000D03*
G54D62*
X159051Y671661D03*
X133575Y692000D03*
X187050Y663500D03*
X156962Y692037D03*
X187050Y652000D03*
X126500Y706500D03*
X73500Y562200D03*
X190300Y725200D03*
X136500Y728500D03*
X181475Y713000D03*
X193475Y706000D03*
X69000Y669745D03*
X108601Y627084D03*
X101309Y675500D03*
X118079Y639954D03*
X131500Y634500D03*
X192582Y733000D03*
X181475Y747000D03*
X87500Y634700D03*
X99051Y635051D03*
X106977Y561919D03*
X90680Y561766D03*
X114000Y591000D03*
X97000Y569153D03*
X65570Y734500D03*
X74075Y732000D03*
X128000Y694500D03*
X175475Y668500D03*
X95032Y660000D03*
X93025Y738000D03*
X88300Y639800D03*
X134575Y659000D03*
X182500Y641600D03*
X14925Y669000D03*
X141900Y645410D03*
X117500Y689900D03*
X112070Y499790D03*
X59475Y688975D03*
X14925Y690000D03*
X103037Y624462D03*
X150300Y645900D03*
X167642Y682217D03*
X128065Y725566D03*
X127983Y736234D03*
X146000Y729000D03*
X167060Y692500D03*
X171500Y743500D03*
X68100Y721000D03*
X171580Y716500D03*
X125075Y715000D03*
X115788Y573787D03*
X52977Y662650D03*
X58612Y740500D03*
X60000Y696984D03*
X98780Y617000D03*
X114857Y741500D03*
X17458Y737184D03*
X171586Y735683D03*
X171440Y708767D03*
X125352Y749277D03*
X119000Y734000D03*
X120000Y581500D03*
X32728Y679000D03*
X167679Y674254D03*
X166547Y663500D03*
X171977Y656850D03*
X124499Y660000D03*
X123401Y669102D03*
X100505Y561919D03*
X95184Y493787D03*
X83300Y624100D03*
X121500Y557500D03*
X79293Y523513D03*
X87500Y522800D03*
X20452Y513547D03*
X144335Y509166D03*
X27580Y528341D03*
X138532Y507500D03*
X126185Y688915D03*
X126070Y493931D03*
X86000Y680000D03*
X30380Y648320D03*
X144324Y498325D03*
X145193Y504232D03*
X96275Y519750D03*
X86000Y688000D03*
X98040Y506730D03*
X69350Y711940D03*
X118490Y495330D03*
X96502Y501930D03*
X84723Y532202D03*
X111000Y506000D03*
X167190Y529510D03*
X153725Y514500D03*
X32720Y660000D03*
X52977Y681650D03*
X63070Y652400D03*
X25023Y663850D03*
Y669850D03*
G54D61*
X187900Y675200D03*
G54D60*
X42717Y597091D03*
%LPD*%
G75*
G54D10*
X-58189Y19685D03*
Y619685D03*
Y1307087D03*
X20000Y1307000D03*
X44000Y17500D03*
X178500D03*
X865353Y19685D03*
Y1307087D03*
G54D20*
X18244Y180800D03*
X29844D03*
X18195Y190606D03*
X29795D03*
X18251Y200306D03*
X29851D03*
X16232Y916362D03*
X27832D03*
X16232Y905862D03*
X27832D03*
X16232Y926862D03*
X27832D03*
X69600Y358228D03*
X58000D03*
X69600Y348228D03*
X58000D03*
X69600Y368228D03*
X58000D03*
X71874Y1081751D03*
X60274D03*
X71874Y1071251D03*
X60274D03*
X71874Y1092251D03*
X60274D03*
X125900Y1077600D03*
Y1088100D03*
Y1098600D03*
X132600Y358028D03*
X144200D03*
X132600Y348028D03*
X144200D03*
X132600Y368028D03*
X144200D03*
X137500Y1077600D03*
Y1088100D03*
Y1098600D03*
X170200Y187500D03*
Y197500D03*
X170100Y207400D03*
X167700Y912000D03*
Y932772D03*
Y922500D03*
X181800Y187500D03*
Y197500D03*
X181700Y207400D03*
X179300Y912000D03*
Y932772D03*
Y922500D03*
G54D11*
X-58431Y824000D03*
X-63431Y837184D03*
Y1152816D03*
X-58431Y1166000D03*
X-53431Y837184D03*
Y1152816D03*
X-27318Y824000D03*
X-32318Y837184D03*
X-22318D03*
X-32318Y1152816D03*
X-22318D03*
X-27318Y1166000D03*
G54D30*
X15000Y271043D03*
Y998543D03*
X66561Y276685D03*
X67061Y1003457D03*
X136482Y269771D03*
Y999692D03*
X175858Y276685D03*
Y1003457D03*
G54D21*
X18351Y208906D03*
X25351D03*
X16462Y935899D03*
X23462D03*
X69500Y339300D03*
X62500D03*
X71649Y1062686D03*
X64649D03*
X134000Y339000D03*
X141000D03*
X131000Y1069000D03*
X138000D03*
X172177Y941600D03*
X179400Y215900D03*
X172400D03*
X179177Y941600D03*
G54D12*
X3005Y30675D03*
X7500Y44000D03*
X3005Y50675D03*
Y70675D03*
Y90675D03*
Y110675D03*
Y130675D03*
Y150675D03*
Y170675D03*
X8908Y163243D03*
Y160243D03*
X3005Y190675D03*
Y210675D03*
X9400Y241516D03*
X3005Y230675D03*
Y250675D03*
Y270675D03*
X10500Y274500D03*
X11800Y284000D03*
X3005Y290675D03*
Y310675D03*
Y330675D03*
Y350675D03*
Y370675D03*
Y390675D03*
Y410675D03*
Y430675D03*
Y450675D03*
Y470675D03*
Y490675D03*
Y510675D03*
Y530675D03*
Y550675D03*
Y570675D03*
Y590675D03*
Y610675D03*
Y630675D03*
Y650675D03*
Y670675D03*
Y690675D03*
Y710675D03*
Y730675D03*
X6025Y734000D03*
X6000Y727000D03*
X3005Y750675D03*
X6025Y748000D03*
Y741000D03*
X3005Y770675D03*
Y790675D03*
Y810675D03*
Y830675D03*
Y850675D03*
Y870675D03*
Y890675D03*
Y910675D03*
Y930675D03*
Y950675D03*
Y970675D03*
X9838Y994729D03*
X3005Y990675D03*
Y1010675D03*
Y1030675D03*
Y1050675D03*
Y1070675D03*
Y1090675D03*
Y1110675D03*
Y1130675D03*
Y1150675D03*
Y1170675D03*
Y1190675D03*
Y1210675D03*
Y1230675D03*
X8000Y1220000D03*
Y1222500D03*
X3005Y1250675D03*
Y1270675D03*
Y1290675D03*
Y1310675D03*
X15868Y3010D03*
X11874Y154893D03*
X13708Y173943D03*
Y170943D03*
X11208Y173943D03*
Y170943D03*
X13080Y179343D03*
Y182343D03*
Y192843D03*
Y189843D03*
X13580Y201643D03*
Y198643D03*
X34544Y192540D03*
X34480Y202243D03*
X14791Y210028D03*
Y207028D03*
X29191Y210428D03*
Y207428D03*
X22170Y246150D03*
X14791Y247715D03*
X17782Y248150D03*
X29390Y246960D03*
X26040Y245190D03*
X29291Y235093D03*
X26791D03*
X31871D03*
X26791Y232593D03*
X29331D03*
X31871D03*
X25545Y248578D03*
X14587Y231944D03*
X17087D03*
X19667D03*
Y229444D03*
X17127D03*
X14587D03*
X12791Y261000D03*
X17953Y267500D03*
X21500D03*
X32716Y273500D03*
X27912Y270676D03*
X32000Y261000D03*
X10000Y267303D03*
X24000Y276000D03*
X21185Y286228D03*
X24185D03*
X27185Y289228D03*
X21185D03*
X24185D03*
X18185D03*
Y312228D03*
X21185D03*
Y315228D03*
X18185D03*
X24185Y312228D03*
X27185D03*
Y315228D03*
X24185D03*
X14000Y335928D03*
X17000D03*
X20000D03*
X23000D03*
X26000D03*
X26500Y358728D03*
X23500D03*
X20500D03*
X17500D03*
Y361728D03*
X26500D03*
X20500D03*
X23500D03*
X11000Y502000D03*
X18000Y491500D03*
X20500Y497500D03*
Y495000D03*
X11000Y511000D03*
X10987Y523418D03*
X29500Y520500D03*
Y512500D03*
X11000Y520000D03*
Y515500D03*
Y506500D03*
X29500Y534075D03*
X28900Y556900D03*
X32258Y646000D03*
X21000Y644000D03*
X32760Y657000D03*
X21525Y660000D03*
Y654000D03*
X12512Y647013D03*
X14925Y663000D03*
X21525Y666500D03*
X32760Y669500D03*
X21525Y672500D03*
X32760Y682000D03*
X13000Y709000D03*
X20453Y708047D03*
X15713Y710009D03*
X17500Y734000D03*
X26500Y732500D03*
X13425Y712500D03*
X17500Y741000D03*
Y748000D03*
X12819Y751500D03*
X12419Y765261D03*
X14830Y763614D03*
X23000Y760000D03*
X12800Y870600D03*
X15600D03*
X12864Y873315D03*
Y876315D03*
Y879315D03*
X15664D03*
Y876315D03*
Y873315D03*
X11700Y907753D03*
Y904753D03*
Y918753D03*
Y915753D03*
X32525Y904241D03*
Y907241D03*
X32825Y917841D03*
Y914841D03*
X12053Y937268D03*
Y934268D03*
X11700Y928753D03*
Y925753D03*
X32625Y925241D03*
Y928241D03*
X27587Y937815D03*
Y934815D03*
X31871Y961865D03*
X26791D03*
X29291D03*
X31871Y959365D03*
X29331D03*
X26791D03*
X14587Y958716D03*
X17087D03*
X19667D03*
Y956216D03*
X17127D03*
X14587D03*
X26990Y975034D03*
X25500Y977500D03*
X14791Y976000D03*
X17500Y974500D03*
X28791Y976919D03*
X27886Y972134D03*
X23702Y992261D03*
X20000Y989000D03*
X23009Y995491D03*
X30522Y1000288D03*
X31791Y993000D03*
X26500Y997500D03*
X15275Y995500D03*
X15000Y1001300D03*
X16985Y1028800D03*
X19985D03*
Y1015800D03*
X16985D03*
X19985Y1012800D03*
X16985D03*
X22985Y1028800D03*
X25985D03*
Y1015800D03*
X22985D03*
X25985Y1012800D03*
X22985D03*
X24685Y1041800D03*
X18185Y1041900D03*
X21385D03*
X24685Y1038800D03*
X21385Y1038900D03*
X18185D03*
X13492Y1049256D03*
Y1051756D03*
Y1046676D03*
X26000Y1062720D03*
X23000D03*
X20000D03*
X17000D03*
X14000D03*
X25000Y1104300D03*
X22000D03*
X19000D03*
Y1107300D03*
X22000D03*
X25000D03*
X11000Y1215000D03*
X10241Y1234150D03*
X11000Y1239500D03*
X23500Y1237000D03*
X12150Y1227850D03*
X16017Y1323770D03*
X34927Y3006D03*
X54927D03*
X47399Y149664D03*
X44399D03*
Y152164D03*
X47399D03*
Y146864D03*
X44399D03*
X34380Y179643D03*
X47487Y171264D03*
X44487D03*
Y174264D03*
X34380Y182643D03*
X34544Y189540D03*
X34480Y199243D03*
X36880Y249217D03*
X42309Y251270D03*
X50967Y246228D03*
X53967D03*
X48477Y233457D03*
X51477D03*
X54477D03*
X39167Y230228D03*
X42167D03*
X51456Y230214D03*
X48456D03*
X54456D03*
X39167Y244728D03*
X42167D03*
X41864Y265636D03*
X38880Y263169D03*
X44500Y272767D03*
X55167Y259228D03*
X52167D03*
X55167Y272228D03*
Y256328D03*
X52167D03*
X40472Y283287D03*
X55650Y280728D03*
X40500Y295500D03*
X47561Y280228D03*
X53343Y301334D03*
X44500Y301500D03*
X52000Y298528D03*
X57430Y298520D03*
X50021Y313863D03*
X52561D03*
Y311363D03*
X50061D03*
X47481D03*
Y313863D03*
X37185Y316228D03*
X40185D03*
Y301728D03*
X37185D03*
X54926Y296651D03*
X53000Y345997D03*
Y348497D03*
Y350997D03*
X55700Y342500D03*
X53000Y364997D03*
Y367497D03*
Y369997D03*
X49689Y474203D03*
X49250Y516750D03*
X37500Y520500D03*
Y512500D03*
X35484Y534075D03*
X45500Y646000D03*
X45240Y669500D03*
X33500Y694425D03*
X34000Y757000D03*
X37000Y756900D03*
X38900Y800200D03*
X52800Y813500D03*
X47813Y833013D03*
X48308Y877415D03*
Y880415D03*
Y883415D03*
X50808Y877415D03*
Y880415D03*
Y883415D03*
X48631Y964607D03*
Y962107D03*
X48731Y959507D03*
Y957007D03*
X42167Y958400D03*
X39167D03*
X48731Y972307D03*
Y974807D03*
X48631Y969707D03*
Y967207D03*
X42367Y972800D03*
X39367D03*
X51164Y988115D03*
Y985115D03*
X48664D03*
Y988115D03*
X35259Y968798D03*
X38500Y977199D03*
X40500Y995000D03*
X39061Y1005000D03*
X40972Y1010059D03*
X38880Y989941D03*
X48492Y1006856D03*
X51852Y1012249D03*
X51164Y994115D03*
Y991115D03*
X48664D03*
Y994115D03*
X42000Y1023000D03*
X44100Y1027850D03*
X50000Y1023000D03*
X53000Y1026000D03*
X48005Y1012038D03*
X37555Y1027168D03*
X40555D03*
X53000Y1021500D03*
X40585Y1041300D03*
X37585D03*
X50561Y1038135D03*
X53061D03*
Y1040635D03*
X50521D03*
X47981D03*
Y1038135D03*
X55700Y1079289D03*
Y1075878D03*
X55701Y1071860D03*
Y1068449D03*
X55635Y1090665D03*
Y1094076D03*
X40500Y1164000D03*
X56000Y1203273D03*
X35517Y1323770D03*
X56017D03*
X61802Y25927D03*
X78400Y40200D03*
Y36700D03*
Y33200D03*
X68508Y50969D03*
X78400Y47200D03*
Y43700D03*
X60475Y79692D03*
X61500Y97500D03*
X76000Y133500D03*
X58700Y110900D03*
X75500Y130000D03*
X76743Y116500D03*
X56967Y246228D03*
X58167Y259228D03*
X61167D03*
X58167Y272228D03*
X61167D03*
X64167D03*
X58167Y256328D03*
X61167D03*
X72500Y283771D03*
X64500Y287000D03*
X56730Y278169D03*
X66561Y273985D03*
X71689Y302000D03*
X64561Y298446D03*
X64765Y314512D03*
Y317012D03*
X62265Y314512D03*
X62225Y317012D03*
X59685D03*
Y314512D03*
X73300Y340600D03*
Y338100D03*
X74700Y346000D03*
Y351000D03*
Y348500D03*
X74428Y370500D03*
Y368000D03*
Y365500D03*
X78500Y410000D03*
X60475Y424728D03*
Y429228D03*
X62216Y412678D03*
X77773Y420228D03*
X58500Y454500D03*
X60773Y457228D03*
X58500Y441000D03*
X71300Y460000D03*
X57000Y483000D03*
X56925Y498000D03*
Y493000D03*
Y488000D03*
Y513500D03*
X78500Y512500D03*
Y504500D03*
X74626Y515080D03*
X56925Y533500D03*
X76500Y531476D03*
X68500Y537075D03*
X72500Y541500D03*
X75396Y544500D03*
X73747Y570715D03*
X74000Y608425D03*
X74857Y611575D03*
X56475Y641000D03*
X78457Y634010D03*
X78677Y637315D03*
X56475Y647000D03*
Y660000D03*
X66400Y655400D03*
X65552Y645503D03*
X56475Y666500D03*
Y679000D03*
Y685000D03*
X65475Y666500D03*
X65500Y671500D03*
X65475Y685000D03*
Y679000D03*
X76500Y704000D03*
Y709500D03*
X61500Y728500D03*
X70925Y732000D03*
X76475Y715000D03*
X74075Y721500D03*
Y726500D03*
X76475Y742500D03*
X70925Y749000D03*
X76500Y746500D03*
X76725Y749500D03*
X58673Y775800D03*
X68694Y764764D03*
X69000Y771500D03*
X77400Y775000D03*
X60000Y797925D03*
X71500Y805500D03*
X77000Y819000D03*
X61000Y810000D03*
X60773Y820614D03*
X71650Y821000D03*
X77000Y823500D03*
X68000Y804606D03*
X62216Y830875D03*
X77018Y836764D03*
X75500Y852500D03*
X73000Y1010500D03*
X56150Y1007500D03*
X72000Y1013500D03*
X65367Y996400D03*
X62367D03*
X56367D03*
X59367D03*
X64108Y1006500D03*
X56245Y1004000D03*
X69802Y1006198D03*
X74000Y1026000D03*
X66000Y1025000D03*
X60185Y1043784D03*
X62725D03*
X65265D03*
Y1041284D03*
X62765D03*
X60185D03*
X76526Y1075845D03*
X76464Y1079181D03*
Y1072947D03*
X76526Y1069611D03*
X75860Y1064323D03*
X75893Y1061138D03*
X61029Y1064153D03*
Y1060742D03*
X76431Y1094565D03*
X76493Y1091229D03*
X64231Y1115268D03*
X62216Y1139950D03*
X77518Y1142650D03*
X68543Y1128650D03*
X77816D03*
X69018Y1147650D03*
X77773Y1147500D03*
X77518Y1138500D03*
X76500Y1162975D03*
X60475Y1152000D03*
X61500Y1160000D03*
X61000Y1172500D03*
X71150Y1165500D03*
X79000Y1157425D03*
Y1173425D03*
X79106Y1176575D03*
X75000Y1196500D03*
X57500Y1181000D03*
X76400Y1188100D03*
X73505Y1200075D03*
X76017Y1323770D03*
X85500Y40000D03*
Y36500D03*
Y33000D03*
X82975Y53333D03*
X84400Y64200D03*
X85500Y47000D03*
Y43500D03*
X99883Y57500D03*
X79500Y86925D03*
X80500Y74000D03*
X88802Y100198D03*
X91059Y94630D03*
X79500Y104425D03*
X79463Y429962D03*
X91500Y434000D03*
X82000Y415000D03*
X84575Y487075D03*
X98925Y515000D03*
X86500Y512500D03*
Y504500D03*
X98925Y524000D03*
Y512500D03*
Y534000D03*
X82000Y531476D03*
X87500D03*
X93000D03*
X102075Y534000D03*
X84050Y555925D03*
X85000Y562148D03*
X91532Y663261D03*
X86000Y676000D03*
Y684000D03*
X101284Y671500D03*
X86000Y700000D03*
Y696000D03*
X93000Y731000D03*
Y745000D03*
X79975Y739975D03*
X99279Y781942D03*
X94000Y818500D03*
X101500Y824271D03*
X92950Y821707D03*
X84000Y844950D03*
X99000Y848000D03*
X80000Y828500D03*
X99000Y853000D03*
X102500Y979500D03*
X79500Y1134000D03*
X91000Y1173425D03*
X81000Y1193425D03*
X86000Y1176575D03*
X94730Y1173910D03*
X96017Y1323770D03*
X111522Y39800D03*
X114522D03*
X122917D03*
Y37300D03*
X111522Y44800D03*
X114522D03*
X111522Y47300D03*
Y49800D03*
X114522D03*
Y52300D03*
X111522D03*
X114522Y47300D03*
X111522Y42300D03*
X114522D03*
X122917Y49800D03*
Y47300D03*
Y44800D03*
Y42300D03*
X123500Y59500D03*
X118475Y83500D03*
X112500Y76000D03*
X112000Y88700D03*
X122500Y102000D03*
X114500Y127000D03*
X103000Y136500D03*
X127482Y312228D03*
X107000Y400425D03*
X118500Y403500D03*
X113000Y394500D03*
X124378Y409308D03*
X110000Y392500D03*
X117500Y398500D03*
X110500Y445000D03*
X104500Y478500D03*
X122000Y463000D03*
X124500Y485000D03*
X119000D03*
X113500D03*
X109000Y500000D03*
X105760Y493500D03*
X105815Y488500D03*
X105732Y496844D03*
X104500Y483425D03*
X113500Y523000D03*
X120000Y512500D03*
Y504500D03*
X108500Y512000D03*
X116000Y529500D03*
X108000Y539500D03*
X109000Y543500D03*
X111000Y555925D03*
X125000Y562500D03*
X106000Y634500D03*
X119500Y707500D03*
X118000Y696000D03*
X119500Y715500D03*
X115525Y731000D03*
Y745000D03*
Y738000D03*
X112294Y754294D03*
X121536Y749253D03*
X121841Y775967D03*
X115563Y759063D03*
X125227Y815000D03*
X120500Y845000D03*
X123000Y829114D03*
X119500Y992000D03*
X127182Y1039000D03*
X121072Y1077500D03*
Y1075000D03*
Y1072500D03*
Y1094500D03*
Y1092000D03*
Y1097000D03*
X110000Y1128425D03*
X121000Y1131575D03*
Y1128425D03*
X112941Y1146240D03*
X124500Y1148575D03*
X123500Y1137500D03*
X118000Y1151575D03*
X123000Y1181000D03*
X125000Y1198000D03*
X116017Y1323770D03*
X146740Y3016D03*
X141748Y26922D03*
X125917Y39800D03*
Y37300D03*
X135014Y50977D03*
X125917Y49800D03*
Y47300D03*
Y44800D03*
Y42300D03*
X142727Y79842D03*
X127000Y77500D03*
X142727Y94000D03*
X134525Y107842D03*
X132350Y94273D03*
X142000Y98842D03*
X141327Y115542D03*
X125500Y118000D03*
X127500Y129500D03*
X141890Y246451D03*
X128000Y251000D03*
X137495Y248875D03*
X138198Y231944D03*
X140778D03*
X143358D03*
Y229444D03*
X140818D03*
X138238D03*
X133529Y265385D03*
X147393Y265728D03*
X136500Y261000D03*
X142400Y269800D03*
X139435Y266728D03*
X145982Y268287D03*
X136482Y272471D03*
X127482Y289228D03*
X133482D03*
X130482D03*
X136482D03*
X133482Y286228D03*
X130482D03*
X133482Y315228D03*
Y312228D03*
X130482Y315228D03*
Y312228D03*
X146482Y316228D03*
X127482Y315228D03*
X146482Y301728D03*
X130200Y339900D03*
Y337400D03*
X144600Y337100D03*
Y339828D03*
X128000Y348300D03*
X127900Y345100D03*
Y364300D03*
Y351800D03*
X127800Y370900D03*
X127900Y367900D03*
X141327Y398000D03*
X136000Y429941D03*
X129314Y414545D03*
X145327Y416500D03*
X142727Y428000D03*
X132850Y421837D03*
X125500Y469600D03*
X135500Y485024D03*
X130000Y485025D03*
X148000Y483000D03*
X134000Y501000D03*
X141500Y516500D03*
X128000Y512500D03*
Y504500D03*
X128500Y554925D03*
X135500Y562500D03*
X133491Y560490D03*
X135000Y637500D03*
X139150Y712500D03*
X136500Y742000D03*
X144827Y763510D03*
X129705Y777796D03*
X129285Y781799D03*
X128500Y791500D03*
X142727D03*
X141993Y800295D03*
X132370Y788872D03*
X128500Y786500D03*
X138428Y806903D03*
X141088Y804709D03*
X133246Y811300D03*
X142999Y842350D03*
X148281Y838882D03*
X145600Y838100D03*
X146000Y854500D03*
X138278Y961865D03*
X140778D03*
X143358D03*
Y959365D03*
X140818D03*
X138278D03*
X129112Y978769D03*
X142000Y977500D03*
X138605Y977649D03*
X146644Y1007363D03*
X133529Y995306D03*
X136482Y1002392D03*
X147393Y995649D03*
X139435Y989500D03*
Y996649D03*
X145982Y998208D03*
X149500Y1023000D03*
X131882Y1012900D03*
X134882D03*
X131882Y1015900D03*
X134882D03*
X125882Y1012900D03*
X128882D03*
X125882Y1015900D03*
X128882D03*
X146482Y1028500D03*
X127182Y1055000D03*
Y1042000D03*
X133382Y1055000D03*
Y1042000D03*
Y1039000D03*
X130382Y1055000D03*
Y1042000D03*
Y1039000D03*
X146482Y1043000D03*
X126760Y1071023D03*
X126793Y1067838D03*
X143072Y1073000D03*
Y1075500D03*
Y1078000D03*
X141572Y1067900D03*
Y1070400D03*
X143072Y1092500D03*
Y1095000D03*
Y1097500D03*
X127000Y1143000D03*
X141649Y1141500D03*
X135500Y1143441D03*
X142088Y1131281D03*
X127000Y1157025D03*
X132350Y1156741D03*
X142727Y1151000D03*
X127000Y1166000D03*
X126360Y1185947D03*
X142500Y1183500D03*
X125440Y1175970D03*
X142500Y1176000D03*
X135000Y1197500D03*
X136017Y1323770D03*
X165799Y3002D03*
X148576Y146649D03*
X151576D03*
Y149149D03*
X148576D03*
X154576Y146649D03*
Y149149D03*
X149664Y174443D03*
Y171443D03*
Y168443D03*
Y165443D03*
X165164Y186143D03*
Y189143D03*
X164964Y199543D03*
Y196543D03*
X164864Y208443D03*
Y205443D03*
X168564Y217543D03*
Y214543D03*
X150500Y247000D03*
X153022Y232593D03*
X150482D03*
X155562D03*
X165562Y230593D03*
X163022D03*
X150482Y235093D03*
X152982D03*
X155562D03*
X165858Y244728D03*
X162858D03*
X152500Y249501D03*
X161200Y251200D03*
X159430Y244830D03*
X161105Y266081D03*
X155482Y266228D03*
X149000Y250000D03*
X149769Y283287D03*
X164947Y280728D03*
X152420Y296500D03*
X167000Y296310D03*
X156858Y280228D03*
X166499Y276483D03*
X169358Y286228D03*
X160777Y275688D03*
X149500Y295500D03*
X160000Y298500D03*
X156778Y311363D03*
Y313863D03*
X159318D03*
X161858D03*
Y311363D03*
X159358D03*
X149482Y316228D03*
Y301728D03*
X164296Y297723D03*
X162783Y301463D03*
X168982Y314512D03*
X171562D03*
X171522Y317012D03*
X168982D03*
X158858Y329228D03*
X149900Y346300D03*
Y349028D03*
Y351800D03*
Y364300D03*
Y370300D03*
Y367528D03*
X151635Y476202D03*
X154000Y471000D03*
X150575Y494500D03*
Y499500D03*
X150500Y489500D03*
X150575Y524500D03*
X170000Y504500D03*
X169000Y522000D03*
Y514000D03*
X150575Y519500D03*
Y509500D03*
X169000Y535075D03*
X150500Y544500D03*
X150575Y539500D03*
Y529500D03*
X169000Y542075D03*
X169475Y706000D03*
Y733000D03*
Y713000D03*
Y720000D03*
X163925Y756500D03*
X169475Y747000D03*
Y740000D03*
X172000Y751500D03*
X167075Y756500D03*
X151300Y756400D03*
X149000Y854500D03*
X149500Y850500D03*
X152364Y890115D03*
Y893115D03*
Y896115D03*
X149864Y890115D03*
Y893115D03*
Y896115D03*
X162877Y910500D03*
Y913500D03*
Y931500D03*
Y934500D03*
Y921500D03*
Y924500D03*
X168177Y940100D03*
X153622Y962514D03*
X151082D03*
Y965014D03*
X153582D03*
X156162D03*
Y962514D03*
X167858Y961800D03*
X164858D03*
X168177Y943100D03*
X149658Y974968D03*
X164758Y976500D03*
X167758D03*
X151000Y981000D03*
X159000Y972500D03*
X152823Y978573D03*
X160732Y977966D03*
X161581Y995673D03*
X149769Y1010059D03*
X164947Y1007500D03*
X164337Y1002475D03*
X156858Y1007000D03*
X166358Y1004941D03*
X155482Y996149D03*
X169358Y1013000D03*
X161884Y1026048D03*
X170929Y1024429D03*
X159500Y1023000D03*
X153150Y1028430D03*
X149482Y1028500D03*
X162500Y1023000D03*
X149482Y1043000D03*
X156778Y1038135D03*
Y1040635D03*
X159318D03*
X161858D03*
Y1038135D03*
X159358D03*
X168982Y1043784D03*
X171522D03*
X171562Y1041284D03*
X168982D03*
X164000Y1171500D03*
X156017Y1323770D03*
X185799Y3002D03*
X193719Y157489D03*
X191219D03*
X192164Y164843D03*
X189664D03*
X192164Y167843D03*
X189664D03*
X192164Y170843D03*
X189664D03*
X192164Y173843D03*
X189664D03*
X186964Y189043D03*
Y186043D03*
Y199543D03*
Y196543D03*
X183582Y217228D03*
Y214228D03*
X186764Y208743D03*
Y205743D03*
X179358Y230328D03*
Y227328D03*
X182358Y230328D03*
X185358D03*
X182358Y227328D03*
X185358D03*
X185658Y243528D03*
X182658D03*
X179658D03*
X181258Y269528D03*
X184258D03*
X187258D03*
X178258D03*
X181067Y256528D03*
X184067D03*
X187067D03*
X178067D03*
X180967Y253728D03*
X177967D03*
X183967D03*
X186967D03*
X178811Y281071D03*
X175858Y273985D03*
X172905Y279728D03*
X173858Y298500D03*
X183500Y299500D03*
X174062Y314512D03*
Y317012D03*
X177458Y335828D03*
X180458D03*
X186458D03*
X183458D03*
X176858Y359790D03*
Y362290D03*
X185858Y359790D03*
X182858D03*
Y362290D03*
X185858D03*
X179858Y359790D03*
Y362290D03*
X189500Y512000D03*
X177000Y522000D03*
Y514000D03*
X191575Y518500D03*
Y524000D03*
X179000Y531925D03*
X189250Y541750D03*
X194000Y550000D03*
X179000Y535075D03*
X191500Y529500D03*
X187500Y643500D03*
X176000Y659500D03*
X175500Y651500D03*
X187050Y659500D03*
X180500Y684500D03*
X182500Y688000D03*
X175500Y672500D03*
X179000Y676500D03*
X187925Y701000D03*
X181000Y696500D03*
X187041Y730000D03*
X181475Y720000D03*
X193000Y754500D03*
X191000Y756500D03*
X184425Y738000D03*
X181475Y740000D03*
X189000Y758500D03*
X173200Y770800D03*
X193964Y887015D03*
Y890015D03*
Y893015D03*
Y896015D03*
X180264Y895915D03*
Y892915D03*
Y889915D03*
X193964Y899015D03*
X184377Y910500D03*
Y913500D03*
X180264Y898915D03*
X183177Y940100D03*
X184377Y931500D03*
Y934500D03*
Y921500D03*
Y924500D03*
X180658Y956100D03*
X186658D03*
Y952900D03*
X180658D03*
X183758Y956200D03*
Y953000D03*
X183177Y943100D03*
X180658Y969000D03*
X186658D03*
X183758Y969100D03*
X182285Y982200D03*
X179285D03*
X188285D03*
X185285D03*
X178811Y1007843D03*
X175858Y1000757D03*
X172905Y1006500D03*
X187658Y995000D03*
Y998000D03*
X184658Y995000D03*
Y998000D03*
X181658Y995000D03*
Y998000D03*
X190158Y995000D03*
Y998000D03*
X182058Y1022519D03*
X173858Y1025500D03*
X174062Y1043784D03*
Y1041284D03*
X190358Y1062764D03*
X187358D03*
X184358D03*
X181358D03*
Y1060064D03*
X184358D03*
X187358D03*
X190358D03*
X186458Y1103662D03*
X183458D03*
X180458D03*
Y1106662D03*
X183458D03*
X192500Y1215000D03*
X182741Y1235150D03*
X183500Y1240500D03*
X176017Y1323770D03*
X194471Y1321882D03*
X199120Y9903D03*
X200536Y29059D03*
Y49059D03*
Y69059D03*
Y109059D03*
Y89059D03*
Y129059D03*
Y149059D03*
Y169059D03*
Y189059D03*
Y209059D03*
Y249059D03*
Y229059D03*
Y269059D03*
Y289059D03*
Y309059D03*
Y329059D03*
Y349059D03*
Y369059D03*
Y409059D03*
Y389059D03*
Y429059D03*
Y449059D03*
Y469059D03*
Y489059D03*
X195000Y490500D03*
X195500Y495000D03*
Y497500D03*
X200536Y509059D03*
Y549059D03*
Y529059D03*
Y569059D03*
Y589059D03*
Y609059D03*
Y629059D03*
Y649059D03*
Y669059D03*
Y709059D03*
Y689059D03*
Y729059D03*
X195000Y752500D03*
X200536Y749059D03*
Y769059D03*
Y789059D03*
Y809059D03*
Y849059D03*
Y829059D03*
Y869059D03*
Y889059D03*
Y909059D03*
Y929059D03*
Y947059D03*
Y969059D03*
Y1009059D03*
Y989059D03*
Y1029059D03*
Y1049059D03*
Y1069059D03*
Y1089059D03*
Y1109059D03*
Y1149059D03*
Y1129059D03*
Y1169059D03*
Y1189059D03*
Y1209059D03*
Y1229059D03*
X195500Y1220000D03*
Y1222500D03*
X200536Y1249059D03*
Y1289059D03*
Y1269059D03*
Y1309059D03*
G54D31*
X12047Y263957D03*
X17953D03*
Y271043D03*
X12047D03*
Y991457D03*
X17953D03*
Y998543D03*
X12047D03*
X69514Y283771D03*
X63608D03*
Y276685D03*
X69514D03*
X70014Y1010543D03*
X64108D03*
Y1003457D03*
X70014D03*
X133529Y262685D03*
X139435D03*
Y269771D03*
X133529D03*
Y992606D03*
X139435D03*
Y999692D03*
X133529D03*
X178811Y283771D03*
X172905D03*
Y276685D03*
X178811D03*
Y1010543D03*
X172905D03*
Y1003457D03*
X178811D03*
G54D22*
X13584Y223012D03*
Y949784D03*
X46478Y304940D03*
X46978Y1031712D03*
X137275Y223012D03*
Y952933D03*
X155775Y304940D03*
Y1031712D03*
G54D13*
X10291Y249166D03*
X7240Y271043D03*
X12000Y641000D03*
X8612Y967317D03*
X8659Y974808D03*
X12047Y1003400D03*
X20650Y248510D03*
X31657Y249042D03*
X27185Y286228D03*
X18185D03*
X20452Y513547D03*
X27580Y528341D03*
X30380Y648320D03*
X32720Y660000D03*
X12389Y653509D03*
X25023Y663850D03*
Y669850D03*
X32728Y679000D03*
X12500D03*
X14925Y669000D03*
Y690000D03*
X20327Y711174D03*
X13375Y730274D03*
X15012Y745563D03*
X17458Y737184D03*
X13500Y862500D03*
X22630Y975714D03*
X31791Y975500D03*
X19500Y1239500D03*
X47487Y174264D03*
X38383Y280119D03*
X47561Y297728D03*
X40000Y334700D03*
X56925Y503000D03*
Y528500D03*
Y508500D03*
Y523500D03*
Y518500D03*
X57000Y538500D03*
X47499Y649000D03*
X52977Y662650D03*
X56475Y654000D03*
X46950Y666500D03*
X45240Y657000D03*
X56475Y672500D03*
X46950D03*
X52977Y681650D03*
X45240Y682000D03*
X57260Y1024020D03*
X48660Y1025650D03*
X68416Y63842D03*
X61000Y84192D03*
X61300Y66900D03*
X69100Y76100D03*
X75173Y78000D03*
X68500Y70000D03*
X71650Y94259D03*
Y111259D03*
X64025Y92575D03*
X65350Y102000D03*
X71500Y130000D03*
X62716Y129542D03*
X66000Y216800D03*
X80500Y273420D03*
X58561Y280728D03*
X74350Y276685D03*
X70000Y298500D03*
X61420Y299310D03*
X68700Y400000D03*
X78500Y406000D03*
X65900Y413000D03*
X69018Y420378D03*
X67000Y430500D03*
X71000Y427000D03*
X60773Y443728D03*
X74979Y437559D03*
X79500Y449925D03*
X65350Y447500D03*
X70500Y443500D03*
X65250Y470378D03*
X74500Y475000D03*
X68000Y463878D03*
X79293Y523513D03*
X75650Y517770D03*
X68345Y533265D03*
X73500Y562200D03*
X63070Y652400D03*
X68000Y664000D03*
X69000Y669745D03*
X68000Y676500D03*
X59475Y688975D03*
X60000Y696984D03*
X69350Y711940D03*
X68100Y721000D03*
X74075Y732000D03*
X65570Y734500D03*
X58612Y740500D03*
X69340Y758500D03*
X66000Y776000D03*
X61576Y762200D03*
X77816Y764764D03*
X78000Y782500D03*
X68481Y800951D03*
X69018Y783764D03*
X62058Y801075D03*
X67993Y827764D03*
X65350Y818654D03*
X71410Y846500D03*
X64500Y943500D03*
X80000Y980649D03*
X59268Y1007793D03*
X74800Y1003457D03*
X62500Y1025500D03*
X71210Y1024290D03*
X68686Y1139993D03*
X64425Y1165500D03*
X64843Y1194000D03*
X74313Y1178559D03*
X64850Y1179000D03*
X99000Y61000D03*
X87500Y83300D03*
X86000Y92000D03*
X94430Y103830D03*
X88900Y119300D03*
X82500Y389500D03*
X84500Y404000D03*
X82500Y398000D03*
X100835Y446500D03*
X91059Y452760D03*
X91593Y439000D03*
X95000Y462740D03*
X85500Y472975D03*
X86500Y481500D03*
X96502Y501930D03*
X95184Y493787D03*
X98040Y506730D03*
X87500Y522800D03*
X96275Y519750D03*
X84723Y532202D03*
X100505Y561919D03*
X97000Y569153D03*
X90680Y561766D03*
X98780Y617000D03*
X99051Y635051D03*
X87500Y634700D03*
X88300Y639800D03*
X83300Y624100D03*
X103037Y624462D03*
X95032Y660000D03*
X86000Y680000D03*
Y688000D03*
X101309Y675500D03*
X93025Y738000D03*
X99500Y787000D03*
X83000Y804000D03*
X94000Y825740D03*
X83000Y810000D03*
X82000Y833575D03*
X104500Y834500D03*
X115918Y75650D03*
X123500Y115500D03*
X123450Y238523D03*
X127482Y286228D03*
X107000Y389500D03*
X107966Y408260D03*
X112441Y418434D03*
X106850Y441596D03*
X125200Y453800D03*
X113500Y476000D03*
X118490Y495330D03*
X126070Y493931D03*
X112070Y499790D03*
X109000Y485000D03*
X111000Y506000D03*
X115788Y573787D03*
X106977Y561919D03*
X121500Y557500D03*
X114000Y591000D03*
X120000Y581500D03*
X108601Y627084D03*
X118079Y639954D03*
X124499Y660000D03*
X126185Y688915D03*
X123401Y669102D03*
X117500Y689900D03*
X126500Y706500D03*
X119000Y734000D03*
X125075Y715000D03*
X125352Y749277D03*
X114857Y741500D03*
X119836Y761664D03*
X107500Y782530D03*
X125654Y772281D03*
X107365Y776004D03*
X118711Y797500D03*
X125500Y820114D03*
X126000Y834500D03*
X117500Y857575D03*
X126500Y1129000D03*
X109500Y1139500D03*
X135500Y70441D03*
X142000Y74575D03*
X142500Y103342D03*
X138650Y94000D03*
X132500Y99000D03*
X135000Y120500D03*
X137449Y113340D03*
X135750Y132750D03*
X133982Y249166D03*
X140870Y249090D03*
X146133Y248610D03*
X144482Y265728D03*
X147500Y278228D03*
X136482Y286228D03*
X150270Y298590D03*
X135245Y407228D03*
X130500Y432500D03*
X139150Y420193D03*
Y429650D03*
X135349Y468652D03*
X135000Y463000D03*
X129000Y468000D03*
X150575Y504500D03*
X144324Y498325D03*
X145193Y504232D03*
X144335Y509166D03*
X138532Y507500D03*
X150575Y534500D03*
X131500Y634500D03*
X150300Y645900D03*
X141900Y645410D03*
X134575Y659000D03*
X128000Y694500D03*
X133575Y692000D03*
X136500Y728500D03*
X128065Y725566D03*
X146000Y729000D03*
X127983Y736234D03*
X133900Y776000D03*
X132350Y793241D03*
X139650Y785905D03*
X139075Y801984D03*
X141327Y822814D03*
X134525Y815114D03*
X134800Y826614D03*
X146505Y978795D03*
X133982Y979087D03*
X147229Y1004299D03*
X144482Y995649D03*
X128700Y999692D03*
X132175Y1117325D03*
X135800Y1138000D03*
X138650Y1149500D03*
X142500Y1161500D03*
X138650Y1165500D03*
X136800Y1194800D03*
X161100Y216500D03*
X155482Y248728D03*
X165014Y268287D03*
X167858Y279310D03*
X157103Y297803D03*
X170358Y298858D03*
X158858Y332228D03*
X153725Y524500D03*
Y514500D03*
X167190Y529510D03*
X171977Y656850D03*
X166547Y663500D03*
X159051Y671661D03*
X167679Y674254D03*
X167642Y682217D03*
X167060Y692500D03*
X171440Y708767D03*
X156962Y692037D03*
X171586Y735683D03*
X171580Y716500D03*
X171500Y743500D03*
X157000Y979000D03*
X164600Y998649D03*
X167858Y1007500D03*
X156858Y1024500D03*
X166207Y1025077D03*
X165500Y1229900D03*
X183600Y276685D03*
X179000Y298500D03*
X189800Y380300D03*
X188516Y518310D03*
X191991Y536336D03*
X191259Y547500D03*
X182500Y641600D03*
X187050Y652000D03*
Y663500D03*
X177500Y679500D03*
X175475Y668500D03*
X181475Y713000D03*
X193475Y706000D03*
X179000Y694000D03*
X190300Y725200D03*
X192582Y733000D03*
X181475Y747000D03*
X183600Y1005700D03*
X178358Y1024062D03*
X186458Y1106662D03*
X192000Y1240500D03*
X182600Y1228850D03*
G54D40*
X42717Y595122D03*
X101772Y178779D03*
Y926810D03*
X160827Y595122D03*
G54D14*
X7000Y256712D03*
X6500Y983484D03*
X19000Y256748D03*
X15000D03*
X30000D03*
X18500Y983484D03*
X14500D03*
X30500D03*
X38229Y256748D03*
X34229D03*
X42309D03*
X55500Y292712D03*
X38500Y983484D03*
X34500D03*
X42500D03*
X72561Y1019484D03*
X56500D03*
X143500Y256748D03*
X127482Y256712D03*
X139500Y256748D03*
X135500D03*
X142500Y986669D03*
X126500D03*
X138500D03*
X134500D03*
X162420Y256748D03*
X158420D03*
X154000D03*
X166420D03*
X167000Y292712D03*
X161920Y986669D03*
X157920D03*
X153500D03*
X166000D03*
X169500Y1019484D03*
X183000Y292712D03*
X181500Y1019484D03*
G54D32*
X25984Y253500D03*
Y980500D03*
X40484Y664500D03*
X40547Y660519D03*
Y656519D03*
X40484Y668500D03*
Y684500D03*
Y680500D03*
Y672500D03*
Y676500D03*
G54D41*
X42717Y597091D03*
X101772Y180748D03*
Y928779D03*
X160827Y597091D03*
G54D50*
X116772Y19685D03*
G54D23*
X16142Y223012D03*
X17717D03*
X19292D03*
X20867D03*
X22442D03*
X24016D03*
X25591D03*
X27166D03*
X28741D03*
X30316D03*
Y241516D03*
X28741D03*
X27166D03*
X25591D03*
X24016D03*
X22442D03*
X20867D03*
X19292D03*
X17717D03*
X16142D03*
Y949784D03*
X17717D03*
X19292D03*
X20867D03*
X22442D03*
X24016D03*
X25591D03*
X27166D03*
X28741D03*
X30316D03*
Y968288D03*
X28741D03*
X27166D03*
X25591D03*
X24016D03*
X22442D03*
X20867D03*
X19292D03*
X17717D03*
X16142D03*
X49036Y304940D03*
X50611D03*
X52186D03*
X53761D03*
Y323444D03*
X52186D03*
X50611D03*
X49036D03*
X49536Y1031712D03*
X51111D03*
X52686D03*
X54261D03*
Y1050216D03*
X52686D03*
X51111D03*
X49536D03*
X55336Y304940D03*
X56910D03*
X58485D03*
X60060D03*
X61635D03*
X63210D03*
Y323444D03*
X61635D03*
X60060D03*
X58485D03*
X56910D03*
X55336D03*
X55836Y1031712D03*
X57410D03*
X58985D03*
X60560D03*
X62135D03*
X63710D03*
Y1050216D03*
X62135D03*
X60560D03*
X58985D03*
X57410D03*
X55836D03*
X139833Y223012D03*
X141408D03*
X142983D03*
X144558D03*
X146133D03*
Y241516D03*
X144558D03*
X142983D03*
X141408D03*
X139833D03*
Y952933D03*
X141408D03*
X142983D03*
X144558D03*
X146133D03*
Y971437D03*
X144558D03*
X142983D03*
X141408D03*
X139833D03*
X147707Y223012D03*
X149282D03*
X150857D03*
X152432D03*
X154007D03*
Y241516D03*
X152432D03*
X150857D03*
X149282D03*
X147707D03*
X158333Y304940D03*
X159908D03*
X161483D03*
X163058D03*
X164633D03*
X166207D03*
X167782D03*
X169357D03*
Y323444D03*
X167782D03*
X166207D03*
X164633D03*
X163058D03*
X161483D03*
X159908D03*
X158333D03*
X147707Y952933D03*
X149282D03*
X150857D03*
X152432D03*
X154007D03*
Y971437D03*
X152432D03*
X150857D03*
X149282D03*
X147707D03*
X158333Y1031712D03*
X159908D03*
X161483D03*
X163058D03*
X164633D03*
X166207D03*
X167782D03*
X169357D03*
Y1050216D03*
X167782D03*
X166207D03*
X164633D03*
X163058D03*
X161483D03*
X159908D03*
X158333D03*
X170932Y304940D03*
X172507D03*
Y323444D03*
X170932D03*
Y1031712D03*
X172507D03*
Y1050216D03*
X170932D03*
G54D15*
X7000Y253745D03*
X6500Y980517D03*
X19000Y253781D03*
X15000D03*
X30000D03*
X18500Y980517D03*
X14500D03*
X30500D03*
X38229Y253781D03*
X34229D03*
X42309D03*
X55500Y289745D03*
X38500Y980517D03*
X34500D03*
X42500D03*
X72561Y1016517D03*
X56500D03*
X143500Y253781D03*
X127482Y253745D03*
X139500Y253781D03*
X135500D03*
X142500Y983702D03*
X126500D03*
X138500D03*
X134500D03*
X162420Y253781D03*
X158420D03*
X154000D03*
X166420D03*
X167000Y289745D03*
X161920Y983702D03*
X157920D03*
X153500D03*
X166000D03*
X169500Y1016517D03*
X183000Y289745D03*
X181500Y1016517D03*
G54D33*
X23017Y253500D03*
Y980500D03*
X37517Y664500D03*
X37580Y660519D03*
Y656519D03*
X37517Y668500D03*
Y684500D03*
Y680500D03*
Y672500D03*
Y676500D03*
G54D51*
X176000Y1231100D03*
Y1236900D03*
G54D42*
X17100Y1233000D03*
X22900D03*
G54D24*
X32874Y223012D03*
Y949784D03*
X65768Y304940D03*
X66268Y1031712D03*
X156565Y223012D03*
Y952933D03*
X175065Y304940D03*
Y1031712D03*
G54D52*
G01X-53431Y837184D02*
X-53771Y837524D01*
Y1131522D01*
X-55299Y1133050D01*
X-62246D01*
X-63771Y1131525D01*
Y837524D01*
X-63431Y837184D01*
G01X7000Y253653D02*
Y251703D01*
X7029Y251674D01*
Y243887D01*
X9400Y241516D01*
G01X12047Y271043D02*
X7240D01*
G01X80000Y980649D02*
Y995000D01*
X74193Y1000807D01*
X37693D01*
X32000Y1006500D01*
X9000D01*
X6500Y1004000D01*
Y989000D01*
X8500Y987000D01*
X18000D01*
X20000Y989000D01*
G01X8659Y974808D02*
X11947Y971520D01*
X14709D01*
G01X10500Y980425D02*
Y978593D01*
X8659Y976752D01*
Y974808D01*
G01X13526Y967317D02*
X8612D01*
G01X6500Y980425D02*
Y978809D01*
X5640Y977949D01*
Y973724D01*
X8074Y967855D01*
X8612Y967317D01*
G01X23178Y250522D02*
X22925Y250775D01*
Y253500D01*
G01X14791Y247715D02*
Y252980D01*
X15000Y253189D01*
Y253689D01*
G01X17782Y248150D02*
Y247460D01*
G01X9400Y241516D02*
X13964D01*
G01X29390Y246960D02*
X28798Y247872D01*
X29946Y253652D01*
X30000Y253689D01*
G01X13973Y245128D02*
X10291Y248810D01*
Y249166D01*
G01X35225Y250685D02*
X38229Y253689D01*
G01X22925Y253500D02*
Y257500D01*
G01X20000Y250500D02*
X19000Y251500D01*
Y253689D01*
G01X31657Y249042D02*
X33125Y252585D01*
X34229Y253689D01*
G01X11000D02*
Y253189D01*
X10291Y252480D01*
Y249166D01*
G01X24000Y276000D02*
Y266828D01*
X25100Y265728D01*
X27502D01*
G01X17953Y263957D02*
Y267500D01*
G01X80500Y273420D02*
Y277000D01*
X77000Y280500D01*
X62542D01*
X57042Y286000D01*
X39500D01*
X34500Y281000D01*
X25747D01*
X21700Y276953D01*
Y270905D01*
X18295Y267500D01*
X17953D01*
G01X21500D02*
Y265500D01*
X23831Y263169D01*
X27502D01*
G01X10500Y274500D02*
X13500D01*
X15000Y273000D01*
Y271043D01*
G01X14791Y976000D02*
Y978184D01*
X14500Y978475D01*
Y980425D01*
G01X17500Y974500D02*
X18291Y973709D01*
Y973002D01*
G01X20021Y975978D02*
X18500Y977499D01*
Y980425D01*
G01X32791Y973000D02*
X34867Y975076D01*
X37421Y975584D01*
X38500Y977199D01*
G01X30500Y980425D02*
Y978628D01*
X28791Y976919D01*
G01X22925Y980500D02*
Y984500D01*
G01X22630Y978254D02*
X22925Y978549D01*
Y980500D01*
G01X34500Y980425D02*
Y978209D01*
X31791Y975500D01*
G01X27502Y992500D02*
X23941D01*
X23702Y992261D01*
G01X20000Y989000D02*
Y989410D01*
X17953Y991457D01*
G01X23009Y995491D02*
X21418Y993900D01*
Y991373D01*
X22850Y989941D01*
X27502D01*
G01X15000Y998543D02*
Y1001300D01*
G01X12047Y998543D02*
Y1003400D01*
G01X19500Y1239500D02*
X28000D01*
X73750Y1193750D01*
X76250D01*
X83500Y1186500D01*
Y1156000D01*
X92499Y1147001D01*
Y1105501D01*
X98000Y1100000D01*
Y1017500D01*
X94000Y1013500D01*
X72000D01*
G01X17100Y1233000D02*
Y1232800D01*
X12150Y1227850D01*
G01X36880Y249217D02*
Y245848D01*
X34317Y243285D01*
X33348D01*
X32291Y242228D01*
G01X41864Y265636D02*
X39272Y268228D01*
X38791D01*
X38732Y268287D01*
X35080D01*
G01X42309Y253689D02*
Y251270D01*
G01D02*
X40648D01*
X38229Y253689D01*
G01X38383Y280119D02*
X40274Y278228D01*
X40561D01*
X40620Y278169D01*
X44272D01*
G01X51850Y280728D02*
X55650D01*
G01X58561D02*
Y281228D01*
X56502Y283287D01*
X51850D01*
G01X45123Y292767D02*
Y295290D01*
X47561Y297728D01*
G01X52000Y298528D02*
Y298025D01*
X49000Y295025D01*
Y292775D01*
G01X41123Y292767D02*
X37061D01*
G01X41123D02*
Y294877D01*
X40500Y295500D01*
G01X44500Y301500D02*
Y301978D01*
X47057Y304535D01*
G01X40500Y295500D02*
X41097Y296393D01*
X46012Y299679D01*
G01X35259Y968798D02*
X34573Y969484D01*
X32775D01*
X32291Y969000D01*
G01X42500Y980425D02*
X38500D01*
G01Y977199D02*
Y980425D01*
G01X40500Y995000D02*
X37899D01*
X37840Y995059D01*
X35080D01*
G01X39061Y1005000D02*
X41061D01*
X41120Y1004941D01*
X44772D01*
G01X52350Y1007500D02*
X56150D01*
G01X59268Y1007793D02*
X57002Y1010059D01*
X52350D01*
G01X38061Y1019539D02*
X42123D01*
G01X42000Y1023000D02*
X42123Y1022877D01*
Y1019539D01*
G01X42000Y1023000D02*
X42415D01*
X46005Y1026590D01*
G01X44100Y1027850D02*
X47250Y1031000D01*
G01X50000Y1023000D02*
Y1019575D01*
G01X46123Y1019539D02*
Y1022562D01*
X46500Y1022939D01*
Y1023490D01*
X48660Y1025650D01*
G01X63608Y283771D02*
Y286108D01*
X64500Y287000D01*
G01X82500Y389500D02*
X100450Y371550D01*
Y294950D01*
X92500Y287000D01*
X64500D01*
G01X72561Y292803D02*
Y295939D01*
X70000Y298500D01*
G01X63057Y295196D02*
X63500Y294753D01*
Y292803D01*
G01X77061D02*
Y296628D01*
X71689Y302000D01*
G01X55500Y292803D02*
X59500D01*
G01D02*
Y294499D01*
X58810Y295189D01*
G01X68061Y292803D02*
Y294946D01*
X64561Y298446D01*
G01X66561Y276685D02*
Y273985D01*
G01X69514Y276685D02*
X74350D01*
G01X65000Y301351D02*
X65440D01*
X67082Y299709D01*
X70000Y298500D01*
G01X71689Y302000D02*
X68060D01*
X67724Y302336D01*
G01X67925Y506000D02*
X64925D01*
X56925Y498000D01*
G01X67925Y501500D02*
X65425D01*
X56925Y493000D01*
G01X67925Y497000D02*
X65925D01*
X56925Y488000D01*
G01X67925Y524000D02*
X65269D01*
X60769Y528500D01*
X56925D01*
G01X67925Y510500D02*
X58925D01*
X56925Y508500D01*
G01X67925Y519500D02*
X63621D01*
X59621Y523500D01*
X56925D01*
G01X67925Y515000D02*
X60425D01*
X56925Y518500D01*
G01X67925Y528500D02*
X67000D01*
X57000Y538500D01*
G01X72000Y1013500D02*
X68192D01*
X65235Y1010543D01*
X64108D01*
G01X67061Y1003457D02*
Y1005098D01*
X68161Y1006198D01*
X69802D01*
G01X70014Y1003457D02*
X74800D01*
G01X60500Y1019575D02*
X56500D01*
G01X57410Y1021909D02*
X56500Y1020999D01*
Y1019575D01*
G01X74000Y1026000D02*
X71693Y1028305D01*
X66595Y1030418D01*
G01X76561Y1019575D02*
Y1023439D01*
X74000Y1026000D01*
G01X66000Y1025000D02*
X68561Y1022439D01*
Y1019575D01*
G01X62500Y1025500D02*
X61500Y1026500D01*
Y1027145D01*
G01X72561Y1019575D02*
Y1022939D01*
X71210Y1024290D01*
G01D02*
X68362Y1027139D01*
X65155Y1028468D01*
G01X64500Y1019575D02*
X59948Y1024127D01*
X58985Y1026451D01*
G01X87500Y83300D02*
Y70700D01*
X81200Y64400D01*
Y61200D01*
X82100Y60300D01*
X86200D01*
X92992Y53508D01*
Y17126D01*
G01X97992D02*
Y53009D01*
X86801Y64200D01*
X84400D01*
G01X88900Y119300D02*
Y128781D01*
X80493Y137188D01*
Y227571D01*
X80500Y229598D01*
Y273420D01*
G01X99000Y848000D02*
X80000Y867000D01*
Y980649D01*
G01X103000Y136500D02*
X116500D01*
X123450Y143450D01*
Y238523D01*
G01D02*
Y256519D01*
X126966Y260035D01*
X135535D01*
X136500Y261000D01*
G01X110000Y392500D02*
Y384000D01*
X102750Y376750D01*
Y294250D01*
X115500Y281500D01*
X143500D01*
X148228Y286228D01*
X169358D01*
G01X104500Y483425D02*
X108775Y479150D01*
X113819D01*
X116767Y476202D01*
X151635D01*
G01X104500Y478500D02*
Y477370D01*
X109806Y472064D01*
X152936D01*
X154000Y471000D01*
G01X108000Y539500D02*
X108500Y540000D01*
X131450D01*
X140950Y549500D01*
X172343D01*
X184000Y537843D01*
Y533000D01*
X191575Y525425D01*
Y524000D01*
G01X191500Y529500D02*
Y531624D01*
X188000Y535124D01*
Y539500D01*
X174500Y553000D01*
X139500D01*
X130000Y543500D01*
X109000D01*
G01X117500Y857575D02*
X122500Y862575D01*
Y986508D01*
X125492Y989500D01*
X139435D01*
G01X192000Y1240500D02*
Y1234500D01*
X146350Y1188850D01*
X124598D01*
X103000Y1167252D01*
Y1105500D01*
X107000Y1101500D01*
Y1014500D01*
X112500Y1009000D01*
X144000D01*
X148000Y1013000D01*
X169358D01*
G01X133982Y249166D02*
Y248558D01*
X137312Y245228D01*
X137920D01*
G01X143868Y247532D02*
X142520Y248880D01*
X141080D01*
X140870Y249090D01*
G01X146133Y248610D02*
Y246460D01*
G01X128000Y251000D02*
X133997Y245003D01*
G01X136482Y269771D02*
Y272471D01*
G01X151193Y265728D02*
X147393D01*
G01X136500Y261000D02*
X138185Y262685D01*
X139435D01*
G01X144482Y265728D02*
Y265228D01*
X146541Y263169D01*
X151193D01*
G01X131500Y253689D02*
X131747Y253094D01*
X132850Y251991D01*
X133190Y251170D01*
Y249958D01*
X133982Y249166D01*
G01X139500Y253689D02*
Y253111D01*
X140870Y251741D01*
Y249090D01*
G01X147500Y253689D02*
X143500D01*
G01X147500D02*
Y252390D01*
X146200Y251090D01*
Y248677D01*
X146133Y248610D01*
G01X127482Y253653D02*
Y251518D01*
X128000Y251000D01*
G01X135500Y253689D02*
X137495Y248875D01*
G01X147500Y278228D02*
X149858D01*
X149917Y278169D01*
X153569D01*
G01X129112Y978769D02*
X131455Y977799D01*
X134999Y974255D01*
G01X126500Y983610D02*
Y981381D01*
X129112Y978769D01*
G01X142000Y977500D02*
X141982Y977482D01*
Y976151D01*
G01X142500Y983610D02*
X146500D01*
G01X146505Y978795D02*
X146133Y979167D01*
Y981633D01*
X146500Y982000D01*
Y983610D01*
G01X143542Y979958D02*
X143000Y980500D01*
X141610D01*
X138500Y983610D01*
G01X138605Y977649D02*
Y979895D01*
X134890Y983610D01*
X134500D01*
G01X137920Y975149D02*
X133982Y979087D01*
G01X130500Y983610D02*
Y982569D01*
X133982Y979087D01*
G01X146644Y1007363D02*
X148199D01*
X150621Y1004941D01*
X153569D01*
G01X136482Y999692D02*
Y1002392D01*
G01X151193Y995649D02*
X147393D01*
G01X139435Y989500D02*
Y992606D01*
G01X144482Y995649D02*
Y995149D01*
X146541Y993090D01*
X151193D01*
G01X128700Y999692D02*
X133529D01*
G01X149500Y1023000D02*
X147500Y1021000D01*
Y1019575D01*
G01X151420Y1019539D02*
X147536D01*
X147500Y1019575D01*
G01X156482Y246228D02*
X157779Y247525D01*
X158098Y248002D01*
X159209Y248222D01*
X161200Y251200D01*
G01X159430Y244830D02*
X157074Y242474D01*
X156228D01*
X155982Y242228D01*
G01X165014Y268287D02*
X158771D01*
G01X154000Y253689D02*
Y251001D01*
X152500Y249501D01*
G01X155482Y248728D02*
X158420Y251666D01*
Y253689D01*
G01X162420D02*
X166420D01*
G01X161200Y251200D02*
X162420Y252420D01*
Y253689D01*
G01X161147Y280728D02*
X164947D01*
G01X157103Y297803D02*
X156420Y297120D01*
Y292767D01*
G01X160500Y292803D02*
Y298000D01*
X160000Y298500D01*
G01X152420Y292767D02*
X148500D01*
G01X152420Y296500D02*
Y292767D01*
G01X171000Y292803D02*
X167000D01*
G01D02*
Y296310D01*
G01X169358Y286228D02*
X170448D01*
X172905Y283771D01*
G01X167858Y279310D02*
Y281228D01*
X165799Y283287D01*
X161147D01*
G01X175000Y292803D02*
Y293075D01*
X172704Y295371D01*
X170618D01*
X169489Y296500D01*
G01X156358Y304228D02*
X150720Y298590D01*
X150270D01*
G01D02*
X149500Y297820D01*
Y295500D01*
G01X170358Y298858D02*
Y300226D01*
G01X152420Y296500D02*
X156095Y300465D01*
X156097Y300467D01*
G01X151635Y476202D02*
X159202D01*
X170000Y487000D01*
X173550D01*
X193856Y507306D01*
Y521719D01*
X191575Y524000D01*
G01X191500Y529500D02*
X193130D01*
X197500Y525130D01*
Y506000D01*
X174850Y483350D01*
X172150D01*
X159800Y471000D01*
X154000D01*
G01X159425Y503000D02*
X155925Y499500D01*
X150575D01*
G01X159425Y498500D02*
X150500Y489575D01*
Y489500D01*
G01X150575Y529500D02*
X152509D01*
X156770Y525239D01*
Y523655D01*
X159425Y521000D01*
G01Y516500D02*
X156425Y519500D01*
X150575D01*
G01Y504500D02*
X156425D01*
X159425Y507500D01*
G01Y512000D02*
X156925Y509500D01*
X150575D01*
G01Y534500D02*
X151309D01*
X159425Y526384D01*
Y525500D01*
G01Y530000D02*
X150575Y538850D01*
Y539500D01*
G01X157920Y983610D02*
Y979920D01*
X157000Y979000D01*
G01X159000Y972500D02*
X158649Y972149D01*
X156293D01*
G01X152823Y978573D02*
Y978823D01*
X153500Y979500D01*
Y983610D01*
G01X161920D02*
X166000D01*
G01X161920D02*
Y979154D01*
X160732Y977966D01*
G01D02*
X158915Y976149D01*
X156482D01*
G01X164600Y998649D02*
X164159Y998208D01*
X158771D01*
G01X161147Y1007500D02*
X164947D01*
G01X167858D02*
Y1008000D01*
X165799Y1010059D01*
X161147D01*
G01X169358Y1013000D02*
X170448D01*
X172905Y1010543D01*
G01X170929Y1024429D02*
X170500Y1024858D01*
Y1026655D01*
G01X155420Y1019539D02*
Y1023062D01*
X156858Y1024500D01*
G01X159500Y1019575D02*
Y1023000D01*
G01X153150Y1028430D02*
Y1028900D01*
X154954Y1030704D01*
X156062D01*
G01X149500Y1023000D02*
X153961Y1025992D01*
X155073Y1026215D01*
X155858Y1027000D01*
G01X165500Y1019575D02*
X169500D01*
G01X165500D02*
Y1021623D01*
G01X168500Y1023000D02*
X169500Y1022000D01*
X171075D01*
X173500Y1019575D01*
G01X175858Y276685D02*
Y273985D01*
G01X173858Y298500D02*
X179000Y293358D01*
Y292803D01*
G01X183000D02*
X182917D01*
X181273Y294447D01*
Y296227D01*
X179000Y298500D01*
G01X187000Y292803D02*
Y296000D01*
X183500Y299500D01*
G01X183600Y276685D02*
X178811D01*
G01X179000Y298500D02*
X176439Y299561D01*
X174000Y302000D01*
X173648D01*
G01X183500Y299500D02*
X177523Y301976D01*
X177449Y302050D01*
G01X175858Y1000757D02*
Y1003457D01*
G01X178811D02*
X181054Y1005700D01*
X183600D01*
G01X173920Y1028500D02*
X174500D01*
X178358Y1024642D01*
Y1024062D01*
G01X181500Y1019575D02*
X178358Y1022717D01*
Y1024062D01*
G01X178142Y1028359D02*
X180697Y1025804D01*
X182058Y1022519D01*
G01X185500Y1019575D02*
X185002D01*
X182058Y1022519D01*
G01X173858Y1025500D02*
Y1023217D01*
X177500Y1019575D01*
G01X176000Y1231100D02*
X180350D01*
X182600Y1228850D01*
G54D25*
X32874Y241516D03*
Y968288D03*
X65768Y323444D03*
X66268Y1050216D03*
X156565Y241516D03*
Y971437D03*
X175065Y323444D03*
Y1050216D03*
G54D43*
X40667Y241228D03*
Y234228D03*
X38685Y305228D03*
Y312228D03*
X40867Y962300D03*
Y969300D03*
X39055Y1030668D03*
Y1037668D03*
X147982Y305228D03*
Y312228D03*
Y1032000D03*
Y1039000D03*
X164358Y241228D03*
Y234228D03*
X166258Y965649D03*
Y972649D03*
G54D34*
X11000Y253780D03*
X10500Y980516D03*
X41123Y289708D03*
X45123D03*
X49000Y289716D03*
X37061Y289708D03*
X42123Y1016480D03*
X46123D03*
X50000Y1016516D03*
X38061Y1016480D03*
X59500Y289744D03*
X63500D03*
X68061D03*
X60500Y1016516D03*
X76561D03*
X64500D03*
X68561D03*
X131500Y253780D03*
X147500D03*
X130500Y983701D03*
X146500D03*
X147500Y1016516D03*
X171000Y289744D03*
X152420Y289708D03*
X156420D03*
X160500Y289744D03*
X148500Y289708D03*
X165500Y1016516D03*
X151420Y1016480D03*
X155420D03*
X159500Y1016516D03*
X187000Y289744D03*
X175000D03*
X179000D03*
X185500Y1016516D03*
X173500D03*
X177500D03*
G54D16*
X30315Y41378D03*
Y404764D03*
Y768150D03*
Y1131536D03*
X173228Y111456D03*
Y474842D03*
Y838228D03*
Y1201614D03*
G54D53*
G01X27912Y270676D02*
X27502Y270266D01*
Y268287D01*
G01X26500Y997500D02*
Y996061D01*
X27502Y995059D01*
G01X35080Y263169D02*
X38880D01*
G01X44272Y283287D02*
X40472D01*
G01X51850Y278169D02*
X56730D01*
G01X44772Y1010059D02*
X40972D01*
G01X35080Y989941D02*
X38880D01*
G01X56245Y1004000D02*
X56061D01*
X55120Y1004941D01*
X52350D01*
G01X151193Y268287D02*
X145982D01*
G01X151193Y998208D02*
X145982D01*
G01X158771Y263169D02*
X161105Y265503D01*
Y266081D01*
G01X153569Y283287D02*
X149769D01*
G01X161147Y278169D02*
X164813D01*
X166499Y276483D01*
G01X161581Y995673D02*
X159557Y993649D01*
X159330D01*
X158771Y993090D01*
G01X153569Y1010059D02*
X149769D01*
G01X161147Y1004941D02*
X166358D01*
G54D44*
X49824Y309468D03*
X50324Y1036240D03*
X159121Y309468D03*
Y1036240D03*
G54D35*
X11000Y256747D03*
X10500Y983483D03*
X41123Y292675D03*
X45123D03*
X49000Y292683D03*
X37061Y292675D03*
X42123Y1019447D03*
X46123D03*
X50000Y1019483D03*
X38061Y1019447D03*
X59500Y292711D03*
X63500D03*
X68061D03*
X60500Y1019483D03*
X76561D03*
X64500D03*
X68561D03*
X131500Y256747D03*
X147500D03*
X130500Y986668D03*
X146500D03*
X147500Y1019483D03*
X171000Y292711D03*
X152420Y292675D03*
X156420D03*
X160500Y292711D03*
X148500Y292675D03*
X165500Y1019483D03*
X151420Y1019447D03*
X155420D03*
X159500Y1019483D03*
X187000Y292711D03*
X175000D03*
X179000D03*
X185500Y1019483D03*
X173500D03*
X177500D03*
G54D17*
G01X15050Y88250D02*
X15072Y88228D01*
G01D02*
X26378D01*
G01X15050Y451470D02*
X15194Y451614D01*
G01D02*
X26378D01*
G01Y815000D02*
X15720D01*
G01X14906Y1178386D02*
X26378D01*
G01X46030Y80310D02*
X45986Y80354D01*
G01D02*
X34252D01*
G01X45930Y443720D02*
X45910Y443740D01*
G01D02*
X34252D01*
G01X45580Y809342D02*
X49200Y805722D01*
Y796800D01*
G01X34252Y807126D02*
X43364D01*
X45580Y809342D01*
G01D02*
Y818720D01*
X56330Y829470D01*
Y843830D01*
G01X34252Y1170512D02*
X48712D01*
G01X158580Y72480D02*
X169291D01*
G01X157810Y435830D02*
X157846Y435866D01*
G01D02*
X169291D01*
G01Y799252D02*
X157822D01*
G01X169291Y1162638D02*
X157862D01*
G01X187626Y64606D02*
X177165D01*
G01X188240Y65220D02*
X187626Y64606D01*
G01X188590Y427930D02*
X188528Y427992D01*
G01D02*
X177165D01*
G01Y791378D02*
X187838D01*
G01X177165Y1154764D02*
X188064D01*
X34252Y64606D03*
Y56732D03*
Y48858D03*
X26378Y64606D03*
Y56732D03*
X34252Y88228D03*
Y80354D03*
Y72480D03*
X26378Y88228D03*
Y80354D03*
Y72480D03*
X34252Y103976D03*
Y96102D03*
X26378Y103976D03*
Y96102D03*
X34252Y412244D03*
Y435866D03*
Y427992D03*
Y420118D03*
X26378Y435866D03*
Y427992D03*
Y420118D03*
X34252Y451614D03*
Y443740D03*
X26378Y451614D03*
Y443740D03*
X34252Y467362D03*
Y459488D03*
X26378Y467362D03*
Y459488D03*
X34252Y775630D03*
Y799252D03*
Y791378D03*
Y783504D03*
X26378Y799252D03*
Y791378D03*
Y783504D03*
X34252Y822874D03*
Y815000D03*
Y807126D03*
X26378Y822874D03*
Y815000D03*
Y807126D03*
X34252Y830748D03*
X26378D03*
X34252Y1146890D03*
Y1139016D03*
X26378Y1146890D03*
X34252Y1170512D03*
Y1162638D03*
Y1154764D03*
X26378Y1170512D03*
Y1162638D03*
Y1154764D03*
X34252Y1194134D03*
Y1186260D03*
Y1178386D03*
X26378Y1194134D03*
Y1186260D03*
Y1178386D03*
X169291Y48858D03*
Y56732D03*
Y64606D03*
Y72480D03*
Y80354D03*
Y88228D03*
Y96102D03*
Y103976D03*
Y412244D03*
Y420118D03*
Y427992D03*
Y435866D03*
Y443740D03*
Y451614D03*
Y459488D03*
Y467362D03*
Y775630D03*
Y783504D03*
Y791378D03*
Y799252D03*
Y807126D03*
Y815000D03*
Y822874D03*
Y830748D03*
Y1139016D03*
Y1146890D03*
Y1154764D03*
Y1162638D03*
Y1170512D03*
Y1178386D03*
Y1186260D03*
Y1194134D03*
X177165Y48858D03*
Y56732D03*
Y64606D03*
Y72480D03*
Y80354D03*
Y88228D03*
Y96102D03*
Y412244D03*
Y420118D03*
Y427992D03*
Y435866D03*
Y443740D03*
Y451614D03*
Y459488D03*
Y775630D03*
Y783504D03*
Y791378D03*
Y799252D03*
Y807126D03*
Y815000D03*
Y822874D03*
Y1139016D03*
Y1146890D03*
Y1154764D03*
Y1162638D03*
Y1170512D03*
Y1178386D03*
Y1186260D03*
G54D26*
X13584Y241516D03*
Y968288D03*
X46478Y323444D03*
X46978Y1050216D03*
X137275Y241516D03*
Y971437D03*
X155775Y323444D03*
Y1050216D03*
G54D54*
G01X87992Y17126D02*
Y30966D01*
X89000Y31974D01*
Y44341D01*
G01X82300Y50400D02*
Y31674D01*
X82992Y30982D01*
Y17126D01*
G54D27*
X17127Y236988D03*
Y233839D03*
Y227540D03*
X29331D03*
Y230689D03*
X17127Y963760D03*
Y960611D03*
Y954312D03*
X29331D03*
Y957461D03*
X50021Y315767D03*
Y318916D03*
X50521Y1045688D03*
Y1042539D03*
X62225Y309468D03*
Y312617D03*
Y318916D03*
X62725Y1036240D03*
Y1039389D03*
Y1045688D03*
X140818Y236988D03*
Y233839D03*
Y227540D03*
Y963760D03*
Y957461D03*
Y966909D03*
X153022Y227540D03*
Y230689D03*
X171522Y309468D03*
Y312617D03*
X159318Y315767D03*
X171522Y318916D03*
X159318D03*
X153022Y957461D03*
Y960610D03*
X171522Y1036240D03*
Y1039389D03*
Y1045688D03*
X159318D03*
Y1042539D03*
G54D45*
X72561Y292803D03*
Y289653D03*
X77061D03*
Y292803D03*
G54D36*
X23016Y257500D03*
Y984500D03*
G54D18*
X26378Y48858D03*
Y412244D03*
Y775630D03*
Y1139016D03*
X177165Y103976D03*
Y467362D03*
Y830748D03*
Y1194134D03*
G54D55*
G01X18500Y983823D02*
X21827Y987150D01*
X24350D01*
X26075Y985425D01*
G54D46*
X71075Y501500D03*
X67925D03*
X71075Y497000D03*
X67925D03*
X71075Y519500D03*
X67925D03*
X71075Y524000D03*
X67925D03*
X71075Y515000D03*
X67925D03*
X71075Y510500D03*
X67925D03*
X71075Y506000D03*
X67925D03*
X71075Y528500D03*
X67925D03*
X162575Y498500D03*
X159425D03*
X162575Y503000D03*
X159425D03*
X162575Y507500D03*
X159425D03*
X162575Y512000D03*
X159425D03*
X162575Y516500D03*
X159425D03*
X162575Y525500D03*
X159425D03*
X162575Y521000D03*
X159425D03*
X162575Y530000D03*
X159425D03*
G54D37*
X25983Y257500D03*
Y984500D03*
G54D28*
X29528Y236988D03*
Y963760D03*
X153219Y236988D03*
Y966909D03*
G54D19*
X15458Y162928D03*
X13837Y887582D03*
X42230Y162928D03*
X40609Y887582D03*
X156214Y169628D03*
X160114Y893200D03*
X182986Y169628D03*
X186886Y893200D03*
G54D56*
G01X72300Y61900D02*
X70400Y60000D01*
X63000D01*
X37000Y34000D01*
X17500D01*
X7500Y44000D01*
G01X7000Y256803D02*
X10964D01*
X11000Y256839D01*
G01X107000Y389500D02*
X97000Y399500D01*
Y455000D01*
X82500Y469500D01*
X73500D01*
X68500Y474500D01*
X63500D01*
X59000Y470000D01*
X48500D01*
X45500Y473000D01*
X13000D01*
X6500Y479500D01*
Y722360D01*
X9000Y724860D01*
Y752500D01*
X12000Y755500D01*
X19000D01*
X21500Y753000D01*
X56270D01*
X58620Y755350D01*
X80350D01*
X88500Y763500D01*
Y840450D01*
X84000Y844950D01*
G01X10500Y983575D02*
X6500D01*
G01X26075Y253500D02*
Y249284D01*
X25545Y248754D01*
Y248578D01*
G01X12791Y261000D02*
X12047Y261744D01*
Y263957D01*
G01X15000Y256839D02*
X19000D01*
G01X34229D02*
X30000D01*
G01X26075Y253500D02*
Y257500D01*
G01D02*
X26736Y256839D01*
X30000D01*
G01X26075Y257500D02*
Y258397D01*
X24322Y260150D01*
X21151D01*
X19000Y257999D01*
Y256839D01*
G01X11000D02*
X15000D01*
G01X17953Y271043D02*
Y285996D01*
G01D02*
X18185Y286228D01*
G01X13760Y501880D02*
X11120D01*
X11000Y502000D01*
G01X14080Y511000D02*
X11000D01*
G01X14130Y523290D02*
X11115D01*
X10987Y523418D01*
G01X23000Y760000D02*
X43000D01*
X44500Y758500D01*
X69340D01*
G01X14500Y983575D02*
X18500D01*
G01X26075Y984500D02*
Y980500D01*
G01X30500Y983575D02*
X29575Y984500D01*
X26075D01*
G01X30500Y983575D02*
X34500D01*
G01X25500Y977500D02*
X26075Y978075D01*
Y980500D01*
G01X14500Y983575D02*
X10500D01*
G01X18500D02*
Y983823D01*
G01X26075Y985425D02*
Y984500D01*
G01X12047Y991457D02*
X11638D01*
X9838Y993257D01*
Y994729D01*
G01X17953Y998543D02*
Y997452D01*
X16001Y995500D01*
X15275D01*
G01X22900Y1233000D02*
Y1236400D01*
X23500Y1237000D01*
G01X51090Y75250D02*
X61750D01*
X70500Y84000D01*
X76000D01*
X80500Y79500D01*
Y74000D01*
G01X76743Y116500D02*
X75243Y118000D01*
X51000D01*
G01X42309Y256839D02*
X38229D01*
G01D02*
X34229D01*
G01X37061Y289617D02*
X41123D01*
G01D02*
X45123D01*
G01D02*
X48992D01*
X49000Y289625D01*
G01D02*
X52500D01*
G01D02*
Y294000D01*
X54926Y296426D01*
Y296651D01*
G01X55500Y289653D02*
X55472Y289625D01*
X52500D01*
G01X82000Y415000D02*
X76000D01*
X67378Y406378D01*
X50022D01*
G01X71300Y460000D02*
X70300Y459000D01*
X65000D01*
X61000Y463000D01*
X53320D01*
X48740Y458420D01*
G01X40575Y668500D02*
Y664500D01*
G01D02*
Y660582D01*
X40638Y660519D01*
G01D02*
Y656519D01*
G01D02*
X44759D01*
X45240Y657000D01*
G01X40575Y676500D02*
Y672500D01*
G01Y684500D02*
Y680500D01*
G01D02*
X43740D01*
X45240Y682000D01*
G01X40575Y676500D02*
Y680500D01*
G01Y672500D02*
Y668500D01*
G01D02*
X44240D01*
X45240Y669500D01*
G01X49200Y796800D02*
Y791300D01*
X52536Y787964D01*
X70758D01*
X73500Y785222D01*
Y778900D01*
X77400Y775000D01*
G01X45915Y858867D02*
X45665Y859117D01*
G01X45915Y858867D02*
X76282Y828500D01*
X80000D01*
G01X34500Y983575D02*
X38500D01*
G01D02*
X42500D01*
G01X38061Y1016389D02*
X42123D01*
G01D02*
X46123D01*
G01D02*
X49964D01*
X50000Y1016425D01*
G01D02*
X53000D01*
G01Y1021500D02*
Y1016425D01*
G01X56500D02*
X53000D01*
G01X49700Y1134000D02*
X79500D01*
G01X76400Y1188100D02*
X50170D01*
G01X89000Y44341D02*
Y52500D01*
X84100Y57400D01*
X76800D01*
X72300Y61900D01*
G01X76000Y133500D02*
X78500Y131000D01*
Y124500D01*
X86302Y116698D01*
Y103102D01*
X81300Y98100D01*
Y91400D01*
X84600Y88100D01*
Y72000D01*
X82600Y70000D01*
X77100D01*
X72300Y65200D01*
Y61900D01*
G01X72500Y283771D02*
X69514D01*
G01X68061Y289653D02*
X63500D01*
G01D02*
X59500D01*
G01D02*
X55500D01*
G01X72561D02*
X68061D01*
G01X77061D02*
X72561D01*
G01X63608Y276685D02*
X58214D01*
X56730Y278169D01*
G01X71075Y501500D02*
Y506000D01*
G01Y497000D02*
Y501500D01*
G01Y519500D02*
Y524000D01*
G01D02*
Y528500D01*
G01Y515000D02*
Y519500D01*
G01Y510500D02*
Y515000D01*
G01Y506000D02*
Y510500D01*
G01Y528500D02*
X71370Y528795D01*
Y534205D01*
X68500Y537075D01*
G01X60000Y797925D02*
Y795100D01*
X61800Y793300D01*
X75100D01*
X83000Y785400D01*
Y763000D01*
X78500Y758500D01*
X69340D01*
G01X68000Y804606D02*
Y806300D01*
X70050Y808350D01*
X73250D01*
X75600Y806000D01*
Y799800D01*
X73725Y797925D01*
X60000D01*
G01X68000Y804606D02*
X66094D01*
X64294Y806406D01*
Y810108D01*
X77000Y822814D01*
Y823500D01*
G01X84000Y844950D02*
X76450Y852500D01*
X75500D01*
G01X73000Y1010500D02*
X72500D01*
X72457Y1010543D01*
X70014D01*
G01X64108Y1003457D02*
Y1006500D01*
G01X60500Y1016425D02*
X56500D01*
G01X60500D02*
X64500D01*
G01D02*
X68561D01*
G01X72561D02*
X68561D01*
G01X76561D02*
X72561D01*
G01X82975Y53333D02*
Y51075D01*
X82300Y50400D01*
G01X102500Y979500D02*
X102650Y979650D01*
Y1100598D01*
X99500Y1103748D01*
Y1167500D01*
X123500Y1191500D01*
X141500D01*
X165500Y1215500D01*
Y1229900D01*
G01X123500Y59500D02*
X128000Y64000D01*
X150100D01*
X158580Y72480D01*
G01X122500Y102000D02*
Y92500D01*
X127500Y87500D01*
X153500D01*
G01X143000Y386000D02*
X130500Y398500D01*
X117500D01*
G01X122000Y463000D02*
X138800Y446200D01*
X153100D01*
G01X123000Y829114D02*
X128113D01*
X130899Y831900D01*
X157500D01*
G01X123500Y1137500D02*
X127000D01*
X148000Y1116500D01*
G01X153000Y1171000D02*
X138500D01*
X128500Y1181000D01*
X123000D01*
G01X132500Y99000D02*
X131500Y100000D01*
Y125500D01*
X127500Y129500D01*
G01X133529Y262685D02*
Y265385D01*
G01X139435Y269771D02*
Y266728D01*
G01X143500Y256839D02*
X147500D01*
G01X139500D02*
X143500D01*
G01X135500D02*
X139500D01*
G01X147500D02*
X150500D01*
G01X131500D02*
X135500D01*
G01X127482Y256803D02*
X131464D01*
X131500Y256839D01*
G01X133900Y776000D02*
X153500D01*
G01X134500Y986760D02*
X138500D01*
G01D02*
X142500D01*
G01D02*
X146500D01*
G01D02*
X150000D01*
G01X134500D02*
X130500D01*
G01D02*
X126500D01*
G01X133529Y992606D02*
Y995306D01*
G01X139435Y999692D02*
Y996649D01*
G01X151420Y1016389D02*
X147536D01*
X147500Y1016425D01*
G01X154000Y256839D02*
X150500D01*
G01X166420D02*
X162420D01*
G01D02*
X158420D01*
G01X154000D02*
X158420D01*
G01X149000Y250000D02*
X150500Y251500D01*
Y256839D01*
G01X148500Y289617D02*
X152420D01*
G01D02*
X156420D01*
G01D02*
X160464D01*
X160500Y289653D01*
G01X175000D02*
X171000D01*
G01D02*
X167000D01*
G01X160500D02*
X163500D01*
G01D02*
Y296927D01*
X164296Y297723D01*
G01X167000Y289653D02*
X163500D01*
G01X162575Y498500D02*
Y503000D01*
G01Y507500D02*
Y512000D01*
G01Y503000D02*
Y507500D01*
G01Y512000D02*
Y516500D01*
G01D02*
Y521000D01*
G01Y525500D02*
Y530000D01*
G01Y521000D02*
Y525500D01*
G01Y530000D02*
Y535650D01*
X169000Y542075D01*
G01X153500Y986760D02*
X157920D01*
G01D02*
X161920D01*
G01D02*
X166000D01*
G01X150000D02*
X153500D01*
G01X151000Y981000D02*
X150000Y982000D01*
Y986760D01*
G01X151420Y1016389D02*
X155420D01*
G01D02*
X159464D01*
X159500Y1016425D01*
G01X173500D02*
X169500D01*
G01X159500D02*
X162500D01*
G01D02*
X165500D01*
G01X162500Y1023000D02*
Y1016425D01*
G01X169500D02*
X165500D01*
G01X178811Y283771D02*
Y281071D01*
G01X172905Y276685D02*
Y279728D01*
G01X179000Y289653D02*
X175000D01*
G01X179000D02*
X183000D01*
G01D02*
X187000D01*
G01X178811Y1010543D02*
Y1007843D01*
G01X172905Y1003457D02*
Y1006500D01*
G01X177500Y1016425D02*
X173500D01*
G01X181500D02*
X177500D01*
G01X185500D02*
X181500D01*
G01X176000Y1236900D02*
X180991D01*
X182741Y1235150D01*
G54D29*
X27502Y268287D03*
Y265728D03*
Y263169D03*
Y995059D03*
Y992500D03*
Y989941D03*
X35080Y268287D03*
Y263169D03*
X44272Y278169D03*
Y283287D03*
X51850Y278169D03*
Y280728D03*
Y283287D03*
X35080Y995059D03*
Y989941D03*
X44772Y1004941D03*
Y1010059D03*
X52350Y1004941D03*
Y1007500D03*
Y1010059D03*
X158771Y268287D03*
Y263169D03*
X151193Y268287D03*
Y265728D03*
Y263169D03*
X153569Y278169D03*
Y283287D03*
X161147Y278169D03*
Y280728D03*
Y283287D03*
X153569Y1004941D03*
Y1010059D03*
X161147Y1004941D03*
Y1007500D03*
Y1010059D03*
X158771Y998208D03*
Y993090D03*
X151193Y998208D03*
Y995649D03*
Y993090D03*
G54D47*
X63000Y1237000D03*
X120000Y267500D03*
X187900Y675200D03*
G54D38*
X21185Y295736D03*
Y321720D03*
X21685Y1022508D03*
Y1048492D03*
X58167Y239736D03*
Y265720D03*
X59367Y963908D03*
Y989892D03*
X130482Y295736D03*
Y321720D03*
Y1022508D03*
Y1048492D03*
X182958Y237136D03*
Y263120D03*
X183800Y962708D03*
Y988692D03*
G54D57*
G01X14709Y971520D02*
X16142Y970087D01*
Y968288D01*
G01X14568D02*
X13647Y967367D01*
X13526Y967317D01*
G01X22442Y241516D02*
Y245038D01*
X22170Y245310D01*
Y246150D01*
G01D02*
X23178Y249622D01*
Y250522D01*
G01X17717Y241516D02*
Y244302D01*
X14791Y247228D01*
Y247715D01*
G01X17782Y247460D02*
X19292Y243812D01*
Y241516D01*
G01X20650Y248510D02*
X20280Y248140D01*
Y244830D01*
X20867Y243412D01*
Y241516D01*
G01X13964D02*
X14568D01*
G01X29390Y246960D02*
X28425Y245995D01*
X27166Y242953D01*
Y241516D01*
G01X31657Y249042D02*
X31813Y247474D01*
X31424Y246383D01*
X29253Y244212D01*
X28741Y242975D01*
Y241516D01*
G01X16142D02*
Y243159D01*
X14173Y245128D01*
X13973D01*
G01X30316Y241516D02*
Y243026D01*
X31478Y244764D01*
X33689Y246975D01*
X35225Y250685D01*
G01X26040Y245190D02*
X25591Y244105D01*
Y241516D01*
G01X20650Y248510D02*
X20000Y249160D01*
Y250500D01*
G01X26990Y975034D02*
X25591Y971653D01*
Y968288D01*
G01X17717D02*
Y971074D01*
X14791Y974000D01*
Y976000D01*
G01X18291Y973002D02*
X19292Y970584D01*
Y968288D01*
G01X20867D02*
Y973935D01*
X20021Y975978D01*
G01X30316Y968288D02*
Y969912D01*
X30749Y970958D01*
X32791Y973000D01*
G01X27166Y968288D02*
Y970396D01*
X27886Y972134D01*
G01X28791Y976919D02*
Y974322D01*
X27886Y972134D01*
G01X22630Y975714D02*
Y972945D01*
X22442Y972297D01*
Y968288D01*
G01X22630Y975714D02*
Y978254D01*
G01X31791Y975500D02*
X28741Y969795D01*
Y968288D01*
G01X32291Y242228D02*
X31890Y241827D01*
Y241516D01*
G01X53343Y301334D02*
X53451Y301379D01*
X53761Y302127D01*
Y304940D01*
G01X47057Y304535D02*
X47462Y304940D01*
G01X47561Y297728D02*
X47914Y297835D01*
X50611Y302880D01*
Y304940D01*
G01X52000Y298528D02*
X51365Y299163D01*
Y301416D01*
X52186Y303398D01*
Y304940D01*
G01X46012Y299679D02*
X49036Y302703D01*
Y304940D01*
G01X32291Y969000D02*
X31890Y968599D01*
Y968288D01*
G01X46005Y1026590D02*
X48760Y1029088D01*
X49536Y1030249D01*
Y1031712D01*
G01X47250Y1031000D02*
X47962Y1031712D01*
G01X52686D02*
Y1030405D01*
X50935Y1026175D01*
X50584Y1024409D01*
X50000Y1023000D01*
G01X48660Y1025650D02*
Y1026160D01*
X49267Y1026767D01*
X51111Y1030218D01*
Y1031712D01*
G01X53000Y1026000D02*
X54261Y1027261D01*
Y1031712D01*
G01X58485Y304940D02*
Y300704D01*
X59885Y297313D01*
X61915Y295958D01*
X63057Y295196D01*
G01X58810Y295189D02*
X57430Y298520D01*
G01X63210Y304940D02*
Y303141D01*
X65000Y301351D01*
G01X67724Y302336D02*
X65402Y303887D01*
X64784Y304505D01*
Y304940D01*
G01X57430Y298520D02*
X56910Y299040D01*
Y304940D01*
G01X64561Y298446D02*
Y299286D01*
X62212Y301635D01*
X61635Y303028D01*
Y304940D01*
G01X61420Y299310D02*
X60060Y302594D01*
Y304940D01*
G01X57410Y1031712D02*
Y1024170D01*
X57260Y1024020D01*
G01D02*
X57410Y1023870D01*
Y1021909D01*
G01X66595Y1030418D02*
X66263D01*
X65902Y1030659D01*
X65284Y1031277D01*
Y1031712D01*
G01X62135D02*
Y1028926D01*
X65061Y1026000D01*
Y1025939D01*
X66000Y1025000D01*
G01X61500Y1027145D02*
X60560Y1029416D01*
Y1031712D01*
G01X65155Y1028468D02*
X63710Y1029913D01*
Y1031712D01*
G01X58985Y1026451D02*
Y1031712D01*
G01X137920Y245228D02*
X139833Y243315D01*
Y241516D01*
G01X141890Y246451D02*
X142983Y243812D01*
Y241516D01*
G01X144558D02*
Y245867D01*
X143868Y247532D01*
G01X146133Y246460D02*
Y241516D01*
G01X133997Y245003D02*
X137641Y242569D01*
X138259Y241951D01*
Y241516D01*
G01X137495Y248875D02*
X137691Y248679D01*
Y248019D01*
X141408Y244302D01*
Y241516D01*
G01X134999Y974255D02*
X137641Y972490D01*
X138259Y971872D01*
Y971437D01*
G01X141982Y976151D02*
X142983Y973733D01*
Y971437D01*
G01X146505Y978795D02*
Y978345D01*
X146133Y977973D01*
Y971437D01*
G01X144558D02*
Y977504D01*
X143542Y979958D01*
G01X138605Y977649D02*
X138577Y977621D01*
Y977054D01*
X141408Y974223D01*
Y971437D01*
G01X139833D02*
Y973236D01*
X137920Y975149D01*
G01X150500Y247000D02*
Y246775D01*
X149282Y243833D01*
Y241516D01*
G01X152500Y249501D02*
Y247026D01*
X150857Y243058D01*
Y241516D01*
G01X155482Y248728D02*
X155129Y248621D01*
X152432Y243576D01*
Y241516D01*
G01X154007D02*
Y243753D01*
X156482Y246228D01*
G01X155982Y242228D02*
X155581Y241827D01*
Y241516D01*
G01X169489Y296500D02*
X168217Y297772D01*
X167782Y299960D01*
Y304940D01*
G01X159908D02*
Y302880D01*
X157211Y297835D01*
X157103Y297803D01*
G01X156759Y304940D02*
Y304629D01*
X156358Y304228D01*
G01X160000Y298500D02*
X160419Y298843D01*
X160678Y301453D01*
X161483Y303398D01*
Y304940D01*
G01X170358Y300226D02*
X169357Y302644D01*
Y304940D01*
G01X156097Y300467D02*
X158333Y302703D01*
Y304940D01*
G01X167000Y296310D02*
X166975Y296327D01*
X166207Y300187D01*
Y304940D01*
G01X162783Y301463D02*
X163058Y302127D01*
Y304940D01*
G01X149658Y974968D02*
X149562Y974928D01*
X149282Y974250D01*
Y971437D01*
G01X152432D02*
Y973497D01*
X154714Y977765D01*
X155972Y978797D01*
X156870Y979069D01*
X157000Y979000D01*
G01X156293Y972149D02*
X155581Y971437D01*
G01X150857D02*
Y972979D01*
X151623Y974829D01*
Y975675D01*
X152823Y978573D01*
G01X156482Y976149D02*
X154007Y973674D01*
Y971437D01*
G01X161884Y1026048D02*
X163058Y1028899D01*
Y1031712D01*
G01X170500Y1026655D02*
X169357Y1029416D01*
Y1031712D01*
G01X156858Y1024500D02*
X157211Y1024607D01*
X159908Y1029652D01*
Y1031712D01*
G01X159500Y1023000D02*
X159501Y1025388D01*
X161483Y1030170D01*
Y1031712D01*
G01X156062Y1030704D02*
X156759Y1031401D01*
Y1031712D01*
G01X155858Y1027000D02*
X158333Y1029475D01*
Y1031712D01*
G01X165500Y1021623D02*
X166207Y1024061D01*
Y1025077D01*
G01D02*
Y1031712D01*
G01X167782D02*
Y1029161D01*
X168500Y1027427D01*
Y1023000D01*
G01X173858Y298500D02*
Y299228D01*
X170932Y302154D01*
Y304940D01*
G01X173648Y302000D02*
X172507Y303141D01*
Y304940D01*
G01X177449Y302050D02*
X174699Y303887D01*
X174081Y304505D01*
Y304940D01*
G01X172507Y1031712D02*
Y1029913D01*
X173920Y1028500D01*
G01X174081Y1031712D02*
Y1031277D01*
X174699Y1030659D01*
X178142Y1028359D01*
G01X170932Y1031712D02*
Y1028926D01*
X173858Y1026000D01*
Y1025500D01*
G54D48*
X82992Y17126D03*
X87992D03*
X92992D03*
X97992D03*
G54D39*
X21685Y342406D03*
Y369178D03*
Y1069178D03*
Y1095950D03*
X181858Y342406D03*
Y369178D03*
X183800Y1069214D03*
Y1095986D03*
G54D58*
G01X-320500Y-470483D02*
Y2626000D01*
X2967000D01*
Y-470483D01*
X-320500D01*
G01X329322Y-314459D02*
Y-319459D01*
G01X327865Y-314459D02*
X330779D01*
G01X335689Y-319459D02*
X333155D01*
Y-314459D01*
X335689D01*
G01X334675Y-316876D02*
X333155D01*
G01X338255Y-314459D02*
Y-319459D01*
X340789D01*
G01X344622Y-319626D02*
X344495Y-319542D01*
Y-319376D01*
X344622Y-319292D01*
X344749Y-319376D01*
Y-319542D01*
X344622Y-319626D01*
G01Y-317376D02*
X344495Y-317292D01*
Y-317126D01*
X344622Y-317042D01*
X344749Y-317126D01*
Y-317292D01*
X344622Y-317376D01*
G01X349405Y-321126D02*
X348772Y-320292D01*
X348455Y-319459D01*
Y-316126D01*
X348772Y-315292D01*
X349405Y-314459D01*
G01X354822D02*
X354315Y-314626D01*
X353935Y-315042D01*
X353682Y-315542D01*
X353492Y-316209D01*
X353429Y-316959D01*
X353492Y-317709D01*
X353682Y-318376D01*
X353935Y-318876D01*
X354315Y-319292D01*
X354822Y-319459D01*
X355329Y-319292D01*
X355709Y-318876D01*
X355962Y-318376D01*
X356152Y-317709D01*
X356215Y-316959D01*
X356152Y-316209D01*
X355962Y-315542D01*
X355709Y-315042D01*
X355329Y-314626D01*
X354822Y-314459D01*
G01X358529Y-318459D02*
X358909Y-319042D01*
X359415Y-319376D01*
X359985Y-319459D01*
X360492Y-319376D01*
X360999Y-318959D01*
X361315Y-318459D01*
X361379Y-317959D01*
X361252Y-317376D01*
X360809Y-316959D01*
X360365Y-316792D01*
X359795D01*
G01X360365D02*
X360745Y-316542D01*
X361062Y-316126D01*
X361189Y-315626D01*
X361062Y-315126D01*
X360745Y-314709D01*
X360175Y-314459D01*
X359605Y-314542D01*
X359035Y-314876D01*
G01X365339Y-321126D02*
X365972Y-320292D01*
X366289Y-319459D01*
Y-316126D01*
X365972Y-315292D01*
X365339Y-314459D01*
G01X368729Y-318459D02*
X369109Y-319042D01*
X369615Y-319376D01*
X370185Y-319459D01*
X370692Y-319376D01*
X371199Y-318959D01*
X371515Y-318459D01*
X371579Y-317959D01*
X371452Y-317376D01*
X371009Y-316959D01*
X370565Y-316792D01*
X369995D01*
G01X370565D02*
X370945Y-316542D01*
X371262Y-316126D01*
X371389Y-315626D01*
X371262Y-315126D01*
X370945Y-314709D01*
X370375Y-314459D01*
X369805Y-314542D01*
X369235Y-314876D01*
G01X374019Y-315292D02*
X374399Y-314792D01*
X374842Y-314542D01*
X375349Y-314459D01*
X375982Y-314626D01*
X376425Y-315042D01*
X376552Y-315542D01*
X376489Y-316042D01*
X376235Y-316459D01*
X374969Y-317292D01*
X374399Y-317876D01*
X374019Y-318709D01*
X373892Y-319459D01*
X376552D01*
G01X380195D02*
X380322Y-318376D01*
X380512Y-317459D01*
X380765Y-316626D01*
X381082Y-315709D01*
X381589Y-314459D01*
X379055D01*
G01X384599Y-317792D02*
X386245D01*
G01X389319Y-315292D02*
X389699Y-314792D01*
X390142Y-314542D01*
X390649Y-314459D01*
X391282Y-314626D01*
X391725Y-315042D01*
X391852Y-315542D01*
X391789Y-316042D01*
X391535Y-316459D01*
X390269Y-317292D01*
X389699Y-317876D01*
X389319Y-318709D01*
X389192Y-319459D01*
X391852D01*
G01X394229Y-318459D02*
X394609Y-319042D01*
X395115Y-319376D01*
X395685Y-319459D01*
X396192Y-319376D01*
X396699Y-318959D01*
X397015Y-318459D01*
X397079Y-317959D01*
X396952Y-317376D01*
X396509Y-316959D01*
X396065Y-316792D01*
X395495D01*
G01X396065D02*
X396445Y-316542D01*
X396762Y-316126D01*
X396889Y-315626D01*
X396762Y-315126D01*
X396445Y-314709D01*
X395875Y-314459D01*
X395305Y-314542D01*
X394735Y-314876D01*
G01X401482Y-319459D02*
Y-314459D01*
X399139Y-318042D01*
X402305D01*
G01X404429Y-318709D02*
X404809Y-319126D01*
X405252Y-319376D01*
X405822Y-319459D01*
X406392Y-319292D01*
X406835Y-318959D01*
X407152Y-318376D01*
X407215Y-317709D01*
X407089Y-317042D01*
X406772Y-316626D01*
X406329Y-316292D01*
X405885Y-316209D01*
X405442Y-316292D01*
X404872Y-316626D01*
X405062Y-314459D01*
X406772D01*
G01X414819Y-319459D02*
Y-314459D01*
X417225D01*
G01X416339Y-316876D02*
X414819D01*
G01X419539Y-319459D02*
X421122Y-314459D01*
X422705Y-319459D01*
G01X422135Y-317709D02*
X420109D01*
G01X424892Y-319459D02*
X427552Y-314459D01*
G01X424892D02*
X427552Y-319459D01*
G01X431322Y-319626D02*
X431195Y-319542D01*
Y-319376D01*
X431322Y-319292D01*
X431449Y-319376D01*
Y-319542D01*
X431322Y-319626D01*
G01Y-317376D02*
X431195Y-317292D01*
Y-317126D01*
X431322Y-317042D01*
X431449Y-317126D01*
Y-317292D01*
X431322Y-317376D01*
G01X436105Y-321126D02*
X435472Y-320292D01*
X435155Y-319459D01*
Y-316126D01*
X435472Y-315292D01*
X436105Y-314459D01*
G01X441522D02*
X441015Y-314626D01*
X440635Y-315042D01*
X440382Y-315542D01*
X440192Y-316209D01*
X440129Y-316959D01*
X440192Y-317709D01*
X440382Y-318376D01*
X440635Y-318876D01*
X441015Y-319292D01*
X441522Y-319459D01*
X442029Y-319292D01*
X442409Y-318876D01*
X442662Y-318376D01*
X442852Y-317709D01*
X442915Y-316959D01*
X442852Y-316209D01*
X442662Y-315542D01*
X442409Y-315042D01*
X442029Y-314626D01*
X441522Y-314459D01*
G01X445229Y-318459D02*
X445609Y-319042D01*
X446115Y-319376D01*
X446685Y-319459D01*
X447192Y-319376D01*
X447699Y-318959D01*
X448015Y-318459D01*
X448079Y-317959D01*
X447952Y-317376D01*
X447509Y-316959D01*
X447065Y-316792D01*
X446495D01*
G01X447065D02*
X447445Y-316542D01*
X447762Y-316126D01*
X447889Y-315626D01*
X447762Y-315126D01*
X447445Y-314709D01*
X446875Y-314459D01*
X446305Y-314542D01*
X445735Y-314876D01*
G01X452039Y-321126D02*
X452672Y-320292D01*
X452989Y-319459D01*
Y-316126D01*
X452672Y-315292D01*
X452039Y-314459D01*
G01X455429Y-318459D02*
X455809Y-319042D01*
X456315Y-319376D01*
X456885Y-319459D01*
X457392Y-319376D01*
X457899Y-318959D01*
X458215Y-318459D01*
X458279Y-317959D01*
X458152Y-317376D01*
X457709Y-316959D01*
X457265Y-316792D01*
X456695D01*
G01X457265D02*
X457645Y-316542D01*
X457962Y-316126D01*
X458089Y-315626D01*
X457962Y-315126D01*
X457645Y-314709D01*
X457075Y-314459D01*
X456505Y-314542D01*
X455935Y-314876D01*
G01X460845Y-318876D02*
X461289Y-319292D01*
X461795Y-319459D01*
X462302Y-319292D01*
X462745Y-318792D01*
X463062Y-318042D01*
X463189Y-317292D01*
Y-316376D01*
X463062Y-315626D01*
X462745Y-314959D01*
X462365Y-314626D01*
X461922Y-314459D01*
X461415Y-314626D01*
X461035Y-314959D01*
X460782Y-315459D01*
X460655Y-316126D01*
X460782Y-316709D01*
X461099Y-317292D01*
X461479Y-317626D01*
X461922Y-317709D01*
X462429Y-317542D01*
X462809Y-317126D01*
X463189Y-316376D01*
G01X466895Y-319459D02*
X467022Y-318376D01*
X467212Y-317459D01*
X467465Y-316626D01*
X467782Y-315709D01*
X468289Y-314459D01*
X465755D01*
G01X471299Y-317792D02*
X472945D01*
G01X475829Y-318459D02*
X476209Y-319042D01*
X476715Y-319376D01*
X477285Y-319459D01*
X477792Y-319376D01*
X478299Y-318959D01*
X478615Y-318459D01*
X478679Y-317959D01*
X478552Y-317376D01*
X478109Y-316959D01*
X477665Y-316792D01*
X477095D01*
G01X477665D02*
X478045Y-316542D01*
X478362Y-316126D01*
X478489Y-315626D01*
X478362Y-315126D01*
X478045Y-314709D01*
X477475Y-314459D01*
X476905Y-314542D01*
X476335Y-314876D01*
G01X481119Y-317376D02*
X481562Y-316792D01*
X481942Y-316459D01*
X482449Y-316292D01*
X482892Y-316459D01*
X483209Y-316792D01*
X483462Y-317292D01*
X483525Y-317876D01*
X483462Y-318376D01*
X483209Y-318876D01*
X482829Y-319292D01*
X482385Y-319459D01*
X481879Y-319292D01*
X481435Y-318792D01*
X481182Y-318042D01*
X481119Y-317209D01*
X481245Y-316126D01*
X481435Y-315542D01*
X481752Y-314959D01*
X482195Y-314542D01*
X482639Y-314459D01*
X483082Y-314626D01*
X483399Y-315042D01*
G01X487422Y-319459D02*
Y-314459D01*
X486662Y-315459D01*
G01Y-319459D02*
X488182D01*
G01X493282D02*
Y-314459D01*
X490939Y-318042D01*
X494105D01*
G01X317322Y-249459D02*
Y-324459D01*
X817322D01*
Y-249459D01*
X317322D01*
G01X512322D02*
Y-324459D01*
G01Y-299459D02*
X615322D01*
Y-274459D01*
G01X512322D02*
X615322D01*
G01X622829Y-309459D02*
Y-304459D01*
X624095D01*
X624602Y-304709D01*
X624982Y-305042D01*
X625299Y-305542D01*
X625552Y-306126D01*
X625615Y-306959D01*
X625552Y-307792D01*
X625299Y-308376D01*
X624982Y-308876D01*
X624602Y-309209D01*
X624095Y-309459D01*
X622829D01*
G01X627739D02*
X629322Y-304459D01*
X630905Y-309459D01*
G01X630335Y-307709D02*
X628309D01*
G01X634422Y-304459D02*
Y-309459D01*
G01X632965Y-304459D02*
X635879D01*
G01X640789Y-309459D02*
X638255D01*
Y-304459D01*
X640789D01*
G01X639775Y-306876D02*
X638255D01*
G01X644622Y-309626D02*
X644495Y-309542D01*
Y-309376D01*
X644622Y-309292D01*
X644749Y-309376D01*
Y-309542D01*
X644622Y-309626D01*
G01Y-307376D02*
X644495Y-307292D01*
Y-307126D01*
X644622Y-307042D01*
X644749Y-307126D01*
Y-307292D01*
X644622Y-307376D01*
G01X617322Y-249459D02*
Y-324459D01*
G01X615322Y-249459D02*
Y-324459D01*
G01X622955Y-284459D02*
Y-279459D01*
X624475D01*
X624982Y-279709D01*
X625362Y-280292D01*
X625489Y-280959D01*
X625362Y-281626D01*
X625045Y-282126D01*
X624475Y-282376D01*
X622955D01*
G01X628182Y-284626D02*
X630462Y-279459D01*
G01X632965Y-284459D02*
Y-279459D01*
X635879Y-284459D01*
Y-279459D01*
G01X639522Y-284626D02*
X639395Y-284542D01*
Y-284376D01*
X639522Y-284292D01*
X639649Y-284376D01*
Y-284542D01*
X639522Y-284626D01*
G01Y-282376D02*
X639395Y-282292D01*
Y-282126D01*
X639522Y-282042D01*
X639649Y-282126D01*
Y-282292D01*
X639522Y-282376D01*
G01X617322Y-299459D02*
X817322D01*
G01X622955Y-259459D02*
Y-254459D01*
X624475D01*
X624982Y-254709D01*
X625362Y-255292D01*
X625489Y-255959D01*
X625362Y-256626D01*
X625045Y-257126D01*
X624475Y-257376D01*
X622955D01*
G01X628055Y-259459D02*
Y-254459D01*
X629639D01*
X630145Y-254709D01*
X630462Y-255042D01*
X630589Y-255709D01*
X630462Y-256376D01*
X630082Y-256792D01*
X629639Y-257042D01*
X628055D01*
G01X629639D02*
X630589Y-259459D01*
G01X634422D02*
X633915Y-259376D01*
X633472Y-259042D01*
X633092Y-258542D01*
X632839Y-257959D01*
X632712Y-257292D01*
Y-256626D01*
X632839Y-255959D01*
X633092Y-255376D01*
X633472Y-254876D01*
X633915Y-254542D01*
X634422Y-254459D01*
X634929Y-254542D01*
X635372Y-254876D01*
X635752Y-255376D01*
X636005Y-255959D01*
X636132Y-256626D01*
Y-257292D01*
X636005Y-257959D01*
X635752Y-258542D01*
X635372Y-259042D01*
X634929Y-259376D01*
X634422Y-259459D01*
G01X638255Y-258459D02*
X638572Y-258959D01*
X638952Y-259292D01*
X639395Y-259459D01*
X639902Y-259292D01*
X640282Y-258959D01*
X640662Y-258459D01*
X640789Y-257792D01*
Y-254459D01*
G01X645889Y-259459D02*
X643355D01*
Y-254459D01*
X645889D01*
G01X644875Y-256876D02*
X643355D01*
G01X651115Y-254876D02*
X650735Y-254626D01*
X650292Y-254459D01*
X649785D01*
X649215Y-254709D01*
X648772Y-255126D01*
X648455Y-255626D01*
X648202Y-256459D01*
X648139Y-257209D01*
X648265Y-257959D01*
X648455Y-258459D01*
X648835Y-258959D01*
X649279Y-259292D01*
X649722Y-259459D01*
X650165D01*
X650609Y-259292D01*
X650989Y-259042D01*
X651305Y-258709D01*
G01X654822Y-254459D02*
Y-259459D01*
G01X653365Y-254459D02*
X656279D01*
G01X659922Y-259626D02*
X659795Y-259542D01*
Y-259376D01*
X659922Y-259292D01*
X660049Y-259376D01*
Y-259542D01*
X659922Y-259626D01*
G01Y-257376D02*
X659795Y-257292D01*
Y-257126D01*
X659922Y-257042D01*
X660049Y-257126D01*
Y-257292D01*
X659922Y-257376D01*
G01X617322Y-274459D02*
X817322D01*
G01X734955Y-301959D02*
Y-306959D01*
X737489D01*
G01X740562Y-301959D02*
X742082D01*
G01X741322D02*
Y-306959D01*
G01X740562D02*
X742082D01*
G01X746929Y-304292D02*
X747182Y-304042D01*
X747372Y-303626D01*
X747499Y-303042D01*
X747372Y-302542D01*
X747119Y-302209D01*
X746675Y-301959D01*
X744965D01*
Y-306959D01*
X747055D01*
X747499Y-306626D01*
X747752Y-306126D01*
X747879Y-305542D01*
X747752Y-304959D01*
X747372Y-304459D01*
X746929Y-304292D01*
X744965D01*
G01X751522Y-307126D02*
X751395Y-307042D01*
Y-306876D01*
X751522Y-306792D01*
X751649Y-306876D01*
Y-307042D01*
X751522Y-307126D01*
G01Y-304876D02*
X751395Y-304792D01*
Y-304626D01*
X751522Y-304542D01*
X751649Y-304626D01*
Y-304792D01*
X751522Y-304876D01*
G01X732322Y-299459D02*
Y-324459D01*
G01X779222Y-301959D02*
Y-306959D01*
G01X777765Y-301959D02*
X780679D01*
G01X784322Y-306959D02*
X783942Y-306876D01*
X783562Y-306542D01*
X783309Y-305959D01*
X783182Y-305292D01*
X783309Y-304626D01*
X783562Y-304042D01*
X783942Y-303709D01*
X784322Y-303626D01*
X784702Y-303709D01*
X785082Y-304042D01*
X785335Y-304626D01*
X785399Y-305292D01*
X785335Y-305959D01*
X785082Y-306542D01*
X784702Y-306876D01*
X784322Y-306959D01*
G01X789422D02*
X789042Y-306876D01*
X788662Y-306542D01*
X788409Y-305959D01*
X788282Y-305292D01*
X788409Y-304626D01*
X788662Y-304042D01*
X789042Y-303709D01*
X789422Y-303626D01*
X789802Y-303709D01*
X790182Y-304042D01*
X790435Y-304626D01*
X790499Y-305292D01*
X790435Y-305959D01*
X790182Y-306542D01*
X789802Y-306876D01*
X789422Y-306959D01*
G01X794522D02*
Y-301959D01*
G01X799622Y-307126D02*
X799495Y-307042D01*
Y-306876D01*
X799622Y-306792D01*
X799749Y-306876D01*
Y-307042D01*
X799622Y-307126D01*
G01Y-304876D02*
X799495Y-304792D01*
Y-304626D01*
X799622Y-304542D01*
X799749Y-304626D01*
Y-304792D01*
X799622Y-304876D01*
G01X775322Y-299459D02*
Y-324459D01*
G01Y-274459D02*
Y-299459D01*
G01X777955Y-281959D02*
Y-276959D01*
X779539D01*
X780045Y-277209D01*
X780362Y-277542D01*
X780489Y-278209D01*
X780362Y-278876D01*
X779982Y-279292D01*
X779539Y-279542D01*
X777955D01*
G01X779539D02*
X780489Y-281959D01*
G01X785589D02*
X783055D01*
Y-276959D01*
X785589D01*
G01X784575Y-279376D02*
X783055D01*
G01X787839Y-276959D02*
X789422Y-281959D01*
X791005Y-276959D01*
G01X794522Y-282126D02*
X794395Y-282042D01*
Y-281876D01*
X794522Y-281792D01*
X794649Y-281876D01*
Y-282042D01*
X794522Y-282126D01*
G01Y-279876D02*
X794395Y-279792D01*
Y-279626D01*
X794522Y-279542D01*
X794649Y-279626D01*
Y-279792D01*
X794522Y-279876D01*
G01X798082Y-326159D02*
X798162Y-326084D01*
X798222Y-325959D01*
X798262Y-325784D01*
X798222Y-325634D01*
X798142Y-325534D01*
X798002Y-325459D01*
X797462D01*
Y-326959D01*
X798122D01*
X798262Y-326859D01*
X798342Y-326709D01*
X798382Y-326534D01*
X798342Y-326359D01*
X798222Y-326209D01*
X798082Y-326159D01*
X797462D01*
G01X799482Y-326959D02*
Y-325959D01*
G01Y-326134D02*
X799402Y-326034D01*
X799282Y-325984D01*
X799142Y-325959D01*
X799002Y-326009D01*
X798882Y-326109D01*
X798802Y-326259D01*
X798762Y-326459D01*
X798802Y-326659D01*
X798882Y-326809D01*
X799002Y-326909D01*
X799142Y-326959D01*
X799282Y-326934D01*
X799402Y-326859D01*
X799482Y-326759D01*
G01X800022Y-326784D02*
X800122Y-326884D01*
X800262Y-326959D01*
X800382D01*
X800502Y-326909D01*
X800582Y-326834D01*
X800622Y-326734D01*
X800602Y-326584D01*
X800522Y-326509D01*
X800162Y-326359D01*
X800082Y-326184D01*
X800122Y-326059D01*
X800202Y-325984D01*
X800322Y-325959D01*
X800442Y-325984D01*
X800562Y-326059D01*
G01X801222Y-326284D02*
X801862D01*
X801802Y-326109D01*
X801702Y-326009D01*
X801562Y-325959D01*
X801422Y-325984D01*
X801302Y-326059D01*
X801222Y-326234D01*
X801182Y-326384D01*
Y-326534D01*
X801222Y-326684D01*
X801322Y-326834D01*
X801442Y-326934D01*
X801582Y-326959D01*
X801722Y-326909D01*
X801862Y-326759D01*
G01X802362Y-326959D02*
Y-325459D01*
G01Y-326209D02*
X802462Y-326059D01*
X802582Y-325984D01*
X802702Y-325959D01*
X802882Y-326009D01*
X803002Y-326109D01*
X803082Y-326284D01*
Y-326484D01*
X803042Y-326684D01*
X802962Y-326834D01*
X802822Y-326934D01*
X802702Y-326959D01*
X802582Y-326934D01*
X802462Y-326859D01*
X802362Y-326734D01*
G01X803922Y-326959D02*
X803802Y-326934D01*
X803682Y-326834D01*
X803602Y-326659D01*
X803562Y-326459D01*
X803602Y-326259D01*
X803682Y-326084D01*
X803802Y-325984D01*
X803922Y-325959D01*
X804042Y-325984D01*
X804162Y-326084D01*
X804242Y-326259D01*
X804262Y-326459D01*
X804242Y-326659D01*
X804162Y-326834D01*
X804042Y-326934D01*
X803922Y-326959D01*
G01X805482D02*
Y-325959D01*
G01Y-326134D02*
X805402Y-326034D01*
X805282Y-325984D01*
X805142Y-325959D01*
X805002Y-326009D01*
X804882Y-326109D01*
X804802Y-326259D01*
X804762Y-326459D01*
X804802Y-326659D01*
X804882Y-326809D01*
X805002Y-326909D01*
X805142Y-326959D01*
X805282Y-326934D01*
X805402Y-326859D01*
X805482Y-326759D01*
G01X806042Y-326959D02*
Y-325959D01*
G01Y-326159D02*
X806142Y-326059D01*
X806242Y-325984D01*
X806382Y-325959D01*
X806482Y-325984D01*
X806602Y-326059D01*
G01X807882Y-325459D02*
Y-326959D01*
G01Y-326734D02*
X807802Y-326859D01*
X807682Y-326934D01*
X807542Y-326959D01*
X807382Y-326909D01*
X807262Y-326784D01*
X807182Y-326634D01*
X807162Y-326459D01*
X807182Y-326284D01*
X807262Y-326134D01*
X807382Y-326009D01*
X807542Y-325959D01*
X807682Y-325984D01*
X807782Y-326034D01*
X807882Y-326134D01*
G01X809522Y-326959D02*
Y-325459D01*
X810022D01*
X810182Y-325534D01*
X810282Y-325634D01*
X810322Y-325834D01*
X810282Y-326034D01*
X810162Y-326159D01*
X810022Y-326234D01*
X809522D01*
G01X810022D02*
X810322Y-326959D01*
G01X810822Y-326284D02*
X811462D01*
X811402Y-326109D01*
X811302Y-326009D01*
X811162Y-325959D01*
X811022Y-325984D01*
X810902Y-326059D01*
X810822Y-326234D01*
X810782Y-326384D01*
Y-326534D01*
X810822Y-326684D01*
X810922Y-326834D01*
X811042Y-326934D01*
X811182Y-326959D01*
X811322Y-326909D01*
X811462Y-326759D01*
G01X811962Y-325959D02*
X812322Y-326959D01*
X812682Y-325959D01*
G01X813522Y-327009D02*
X813482Y-326984D01*
Y-326934D01*
X813522Y-326909D01*
X813562Y-326934D01*
Y-326984D01*
X813522Y-327009D01*
G01X814682Y-326959D02*
X814722Y-326634D01*
X814782Y-326359D01*
X814862Y-326109D01*
X814962Y-325834D01*
X815122Y-325459D01*
X814322D01*
G01X816082Y-326159D02*
X816162Y-326084D01*
X816222Y-325959D01*
X816262Y-325784D01*
X816222Y-325634D01*
X816142Y-325534D01*
X816002Y-325459D01*
X815462D01*
Y-326959D01*
X816122D01*
X816262Y-326859D01*
X816342Y-326709D01*
X816382Y-326534D01*
X816342Y-326359D01*
X816222Y-326209D01*
X816082Y-326159D01*
X815462D01*
G01X-320500Y-470483D02*
Y2626000D01*
X2967000D01*
Y-470483D01*
X-320500D01*
G01X331395Y-304184D02*
X330925Y-303869D01*
X330377Y-303659D01*
X329750D01*
X329045Y-303974D01*
X328497Y-304499D01*
X328105Y-305129D01*
X327792Y-306179D01*
X327714Y-307124D01*
X327870Y-308069D01*
X328105Y-308699D01*
X328575Y-309329D01*
X329124Y-309749D01*
X329672Y-309959D01*
X330220D01*
X330769Y-309749D01*
X331239Y-309434D01*
X331630Y-309014D01*
G01X335032Y-303659D02*
X336912D01*
G01X335972D02*
Y-309959D01*
G01X335032D02*
X336912D01*
G01X342272Y-303659D02*
Y-309959D01*
G01X340470Y-303659D02*
X344074D01*
G01X348572Y-309959D02*
Y-307124D01*
X347005Y-303659D01*
G01X350139D02*
X348572Y-307124D01*
G01X359449Y-308699D02*
X359919Y-309434D01*
X360545Y-309854D01*
X361250Y-309959D01*
X361877Y-309854D01*
X362504Y-309329D01*
X362895Y-308699D01*
X362974Y-308069D01*
X362817Y-307334D01*
X362269Y-306809D01*
X361720Y-306599D01*
X361015D01*
G01X361720D02*
X362190Y-306284D01*
X362582Y-305759D01*
X362739Y-305129D01*
X362582Y-304499D01*
X362190Y-303974D01*
X361485Y-303659D01*
X360780Y-303764D01*
X360075Y-304184D01*
G01X365749Y-308699D02*
X366219Y-309434D01*
X366845Y-309854D01*
X367550Y-309959D01*
X368177Y-309854D01*
X368804Y-309329D01*
X369195Y-308699D01*
X369274Y-308069D01*
X369117Y-307334D01*
X368569Y-306809D01*
X368020Y-306599D01*
X367315D01*
G01X368020D02*
X368490Y-306284D01*
X368882Y-305759D01*
X369039Y-305129D01*
X368882Y-304499D01*
X368490Y-303974D01*
X367785Y-303659D01*
X367080Y-303764D01*
X366375Y-304184D01*
G01X372049Y-308699D02*
X372519Y-309434D01*
X373145Y-309854D01*
X373850Y-309959D01*
X374477Y-309854D01*
X375104Y-309329D01*
X375495Y-308699D01*
X375574Y-308069D01*
X375417Y-307334D01*
X374869Y-306809D01*
X374320Y-306599D01*
X373615D01*
G01X374320D02*
X374790Y-306284D01*
X375182Y-305759D01*
X375339Y-305129D01*
X375182Y-304499D01*
X374790Y-303974D01*
X374085Y-303659D01*
X373380Y-303764D01*
X372675Y-304184D01*
G01X379915Y-309959D02*
X380072Y-308594D01*
X380307Y-307439D01*
X380620Y-306389D01*
X381012Y-305234D01*
X381639Y-303659D01*
X378505D01*
G01X386215Y-309959D02*
X386372Y-308594D01*
X386607Y-307439D01*
X386920Y-306389D01*
X387312Y-305234D01*
X387939Y-303659D01*
X384805D01*
G01X392515Y-311114D02*
X392829Y-309749D01*
G01X398972Y-303659D02*
Y-309959D01*
G01X397170Y-303659D02*
X400774D01*
G01X403314Y-309959D02*
X405272Y-303659D01*
X407230Y-309959D01*
G01X406525Y-307754D02*
X404019D01*
G01X410632Y-303659D02*
X412512D01*
G01X411572D02*
Y-309959D01*
G01X410632D02*
X412512D01*
G01X415522Y-303659D02*
X416619Y-309959D01*
X417872Y-303659D01*
X419125Y-309959D01*
X420222Y-303659D01*
G01X422214Y-309959D02*
X424172Y-303659D01*
X426130Y-309959D01*
G01X425425Y-307754D02*
X422919D01*
G01X428670Y-309959D02*
Y-303659D01*
X432274Y-309959D01*
Y-303659D01*
G01X442680Y-312059D02*
X441897Y-311009D01*
X441505Y-309959D01*
Y-305759D01*
X441897Y-304709D01*
X442680Y-303659D01*
G01X454105Y-309959D02*
Y-303659D01*
X456064D01*
X456690Y-303974D01*
X457082Y-304394D01*
X457239Y-305234D01*
X457082Y-306074D01*
X456612Y-306599D01*
X456064Y-306914D01*
X454105D01*
G01X456064D02*
X457239Y-309959D01*
G01X461972Y-310169D02*
X461815Y-310064D01*
Y-309854D01*
X461972Y-309749D01*
X462129Y-309854D01*
Y-310064D01*
X461972Y-310169D01*
G01X468272Y-309959D02*
X467645Y-309854D01*
X467097Y-309434D01*
X466627Y-308804D01*
X466314Y-308069D01*
X466157Y-307229D01*
Y-306389D01*
X466314Y-305549D01*
X466627Y-304814D01*
X467097Y-304184D01*
X467645Y-303764D01*
X468272Y-303659D01*
X468899Y-303764D01*
X469447Y-304184D01*
X469917Y-304814D01*
X470230Y-305549D01*
X470387Y-306389D01*
Y-307229D01*
X470230Y-308069D01*
X469917Y-308804D01*
X469447Y-309434D01*
X468899Y-309854D01*
X468272Y-309959D01*
G01X474572Y-310169D02*
X474415Y-310064D01*
Y-309854D01*
X474572Y-309749D01*
X474729Y-309854D01*
Y-310064D01*
X474572Y-310169D01*
G01X482595Y-304184D02*
X482125Y-303869D01*
X481577Y-303659D01*
X480950D01*
X480245Y-303974D01*
X479697Y-304499D01*
X479305Y-305129D01*
X478992Y-306179D01*
X478914Y-307124D01*
X479070Y-308069D01*
X479305Y-308699D01*
X479775Y-309329D01*
X480324Y-309749D01*
X480872Y-309959D01*
X481420D01*
X481969Y-309749D01*
X482439Y-309434D01*
X482830Y-309014D01*
G01X487172Y-310169D02*
X487015Y-310064D01*
Y-309854D01*
X487172Y-309749D01*
X487329Y-309854D01*
Y-310064D01*
X487172Y-310169D01*
G01X493864Y-312059D02*
X494647Y-311009D01*
X495039Y-309959D01*
Y-305759D01*
X494647Y-304709D01*
X493864Y-303659D01*
G01X330142Y-296809D02*
X331709D01*
Y-298699D01*
X331239Y-299329D01*
X330690Y-299749D01*
X329907Y-299959D01*
X329124Y-299749D01*
X328575Y-299329D01*
X328105Y-298699D01*
X327792Y-297964D01*
X327635Y-297124D01*
Y-296389D01*
X327792Y-295759D01*
X328105Y-295024D01*
X328575Y-294394D01*
X329045Y-293974D01*
X329672Y-293659D01*
X330220D01*
X330847Y-293869D01*
X331317Y-294289D01*
G01X334249Y-293659D02*
Y-298174D01*
X334562Y-299119D01*
X335189Y-299749D01*
X335972Y-299959D01*
X336755Y-299749D01*
X337382Y-299119D01*
X337695Y-298174D01*
Y-293659D01*
G01X341332D02*
X343212D01*
G01X342272D02*
Y-299959D01*
G01X341332D02*
X343212D01*
G01X346927Y-299119D02*
X347554Y-299644D01*
X348259Y-299959D01*
X348885D01*
X349512Y-299644D01*
X349982Y-299119D01*
X350217Y-298384D01*
X350060Y-297649D01*
X349669Y-297019D01*
X348964Y-296599D01*
X348024Y-296389D01*
X347475Y-295969D01*
X347240Y-295234D01*
X347397Y-294499D01*
X347789Y-293974D01*
X348337Y-293659D01*
X348885D01*
X349434Y-293869D01*
X349904Y-294394D01*
G01X353227Y-299959D02*
Y-293659D01*
G01X356517D02*
Y-299959D01*
G01Y-296809D02*
X353227D01*
G01X359214Y-299959D02*
X361172Y-293659D01*
X363130Y-299959D01*
G01X362425Y-297754D02*
X359919D01*
G01X365670Y-299959D02*
Y-293659D01*
X369274Y-299959D01*
Y-293659D01*
G01X378349Y-299959D02*
Y-293659D01*
X379915D01*
X380542Y-293974D01*
X381012Y-294394D01*
X381404Y-295024D01*
X381717Y-295759D01*
X381795Y-296809D01*
X381717Y-297859D01*
X381404Y-298594D01*
X381012Y-299224D01*
X380542Y-299644D01*
X379915Y-299959D01*
X378349D01*
G01X385432Y-293659D02*
X387312D01*
G01X386372D02*
Y-299959D01*
G01X385432D02*
X387312D01*
G01X391027Y-299119D02*
X391654Y-299644D01*
X392359Y-299959D01*
X392985D01*
X393612Y-299644D01*
X394082Y-299119D01*
X394317Y-298384D01*
X394160Y-297649D01*
X393769Y-297019D01*
X393064Y-296599D01*
X392124Y-296389D01*
X391575Y-295969D01*
X391340Y-295234D01*
X391497Y-294499D01*
X391889Y-293974D01*
X392437Y-293659D01*
X392985D01*
X393534Y-293869D01*
X394004Y-294394D01*
G01X398972Y-293659D02*
Y-299959D01*
G01X397170Y-293659D02*
X400774D01*
G01X405272Y-300169D02*
X405115Y-300064D01*
Y-299854D01*
X405272Y-299749D01*
X405429Y-299854D01*
Y-300064D01*
X405272Y-300169D01*
G01X411415Y-301114D02*
X411729Y-299749D01*
G01X417872Y-293659D02*
Y-299959D01*
G01X416070Y-293659D02*
X419674D01*
G01X422214Y-299959D02*
X424172Y-293659D01*
X426130Y-299959D01*
G01X425425Y-297754D02*
X422919D01*
G01X430472Y-299959D02*
X429845Y-299854D01*
X429297Y-299434D01*
X428827Y-298804D01*
X428514Y-298069D01*
X428357Y-297229D01*
Y-296389D01*
X428514Y-295549D01*
X428827Y-294814D01*
X429297Y-294184D01*
X429845Y-293764D01*
X430472Y-293659D01*
X431099Y-293764D01*
X431647Y-294184D01*
X432117Y-294814D01*
X432430Y-295549D01*
X432587Y-296389D01*
Y-297229D01*
X432430Y-298069D01*
X432117Y-298804D01*
X431647Y-299434D01*
X431099Y-299854D01*
X430472Y-299959D01*
G01X436772D02*
Y-297124D01*
X435205Y-293659D01*
G01X438339D02*
X436772Y-297124D01*
G01X441349Y-293659D02*
Y-298174D01*
X441662Y-299119D01*
X442289Y-299749D01*
X443072Y-299959D01*
X443855Y-299749D01*
X444482Y-299119D01*
X444795Y-298174D01*
Y-293659D01*
G01X447414Y-299959D02*
X449372Y-293659D01*
X451330Y-299959D01*
G01X450625Y-297754D02*
X448119D01*
G01X453870Y-299959D02*
Y-293659D01*
X457474Y-299959D01*
Y-293659D01*
G01X327870Y-289959D02*
Y-283659D01*
X331474Y-289959D01*
Y-283659D01*
G01X335972Y-289959D02*
X335345Y-289854D01*
X334797Y-289434D01*
X334327Y-288804D01*
X334014Y-288069D01*
X333857Y-287229D01*
Y-286389D01*
X334014Y-285549D01*
X334327Y-284814D01*
X334797Y-284184D01*
X335345Y-283764D01*
X335972Y-283659D01*
X336599Y-283764D01*
X337147Y-284184D01*
X337617Y-284814D01*
X337930Y-285549D01*
X338087Y-286389D01*
Y-287229D01*
X337930Y-288069D01*
X337617Y-288804D01*
X337147Y-289434D01*
X336599Y-289854D01*
X335972Y-289959D01*
G01X342272Y-290169D02*
X342115Y-290064D01*
Y-289854D01*
X342272Y-289749D01*
X342429Y-289854D01*
Y-290064D01*
X342272Y-290169D01*
G01X347084Y-284709D02*
X347554Y-284079D01*
X348102Y-283764D01*
X348729Y-283659D01*
X349512Y-283869D01*
X350060Y-284394D01*
X350217Y-285024D01*
X350139Y-285654D01*
X349825Y-286179D01*
X348259Y-287229D01*
X347554Y-287964D01*
X347084Y-289014D01*
X346927Y-289959D01*
X350217D01*
G01X354872D02*
Y-283659D01*
X353932Y-284919D01*
G01Y-289959D02*
X355812D01*
G01X361172D02*
Y-283659D01*
X360232Y-284919D01*
G01Y-289959D02*
X362112D01*
G01X367315Y-291114D02*
X367629Y-289749D01*
G01X371422Y-283659D02*
X372519Y-289959D01*
X373772Y-283659D01*
X375025Y-289959D01*
X376122Y-283659D01*
G01X381639Y-289959D02*
X378505D01*
Y-283659D01*
X381639D01*
G01X380385Y-286704D02*
X378505D01*
G01X384570Y-289959D02*
Y-283659D01*
X388174Y-289959D01*
Y-283659D01*
G01X391027Y-289959D02*
Y-283659D01*
G01X394317D02*
Y-289959D01*
G01Y-286809D02*
X391027D01*
G01X397249Y-283659D02*
Y-288174D01*
X397562Y-289119D01*
X398189Y-289749D01*
X398972Y-289959D01*
X399755Y-289749D01*
X400382Y-289119D01*
X400695Y-288174D01*
Y-283659D01*
G01X403314Y-289959D02*
X405272Y-283659D01*
X407230Y-289959D01*
G01X406525Y-287754D02*
X404019D01*
G01X416384Y-284709D02*
X416854Y-284079D01*
X417402Y-283764D01*
X418029Y-283659D01*
X418812Y-283869D01*
X419360Y-284394D01*
X419517Y-285024D01*
X419439Y-285654D01*
X419125Y-286179D01*
X417559Y-287229D01*
X416854Y-287964D01*
X416384Y-289014D01*
X416227Y-289959D01*
X419517D01*
G01X422370D02*
Y-283659D01*
X425974Y-289959D01*
Y-283659D01*
G01X428749Y-289959D02*
Y-283659D01*
X430315D01*
X430942Y-283974D01*
X431412Y-284394D01*
X431804Y-285024D01*
X432117Y-285759D01*
X432195Y-286809D01*
X432117Y-287859D01*
X431804Y-288594D01*
X431412Y-289224D01*
X430942Y-289644D01*
X430315Y-289959D01*
X428749D01*
G01X441505D02*
Y-283659D01*
X443464D01*
X444090Y-283974D01*
X444482Y-284394D01*
X444639Y-285234D01*
X444482Y-286074D01*
X444012Y-286599D01*
X443464Y-286914D01*
X441505D01*
G01X443464D02*
X444639Y-289959D01*
G01X447649D02*
Y-283659D01*
X449215D01*
X449842Y-283974D01*
X450312Y-284394D01*
X450704Y-285024D01*
X451017Y-285759D01*
X451095Y-286809D01*
X451017Y-287859D01*
X450704Y-288594D01*
X450312Y-289224D01*
X449842Y-289644D01*
X449215Y-289959D01*
X447649D01*
G01X455672Y-290169D02*
X455515Y-290064D01*
Y-289854D01*
X455672Y-289749D01*
X455829Y-289854D01*
Y-290064D01*
X455672Y-290169D01*
G01X351972Y-279259D02*
X349452Y-278842D01*
X347247Y-277176D01*
X345357Y-274676D01*
X344097Y-271759D01*
X343467Y-268426D01*
Y-265092D01*
X344097Y-261759D01*
X345357Y-258842D01*
X347247Y-256343D01*
X349452Y-254676D01*
X351972Y-254259D01*
X354492Y-254676D01*
X356697Y-256343D01*
X358587Y-258842D01*
X359847Y-261759D01*
X360477Y-265092D01*
Y-268426D01*
X359847Y-271759D01*
X358587Y-274676D01*
X356697Y-277176D01*
X354492Y-278842D01*
X351972Y-279259D01*
G01X354492Y-272592D02*
X358272Y-279259D01*
G01X371817Y-262593D02*
Y-274259D01*
X373077Y-277176D01*
X374967Y-278842D01*
X377172Y-279259D01*
X379377Y-278842D01*
X381267Y-277176D01*
X382527Y-274259D01*
G01Y-279259D02*
Y-262593D01*
G01X408042Y-279259D02*
Y-262593D01*
G01Y-265509D02*
X406782Y-263843D01*
X404892Y-263009D01*
X402687Y-262593D01*
X400482Y-263426D01*
X398592Y-265092D01*
X397332Y-267593D01*
X396702Y-270926D01*
X397332Y-274259D01*
X398592Y-276760D01*
X400482Y-278426D01*
X402687Y-279259D01*
X404892Y-278842D01*
X406782Y-277593D01*
X408042Y-275926D01*
G01X422217Y-279259D02*
Y-262593D01*
G01Y-266759D02*
X423477Y-264676D01*
X425367Y-263009D01*
X427887Y-262593D01*
X430092Y-263009D01*
X431982Y-264676D01*
X432927Y-267593D01*
Y-279259D01*
G01X452772Y-254259D02*
Y-279259D01*
G01X448362Y-262593D02*
X457182D01*
G01X483642Y-279259D02*
Y-262593D01*
G01Y-265509D02*
X482382Y-263843D01*
X480492Y-263009D01*
X478287Y-262593D01*
X476082Y-263426D01*
X474192Y-265092D01*
X472932Y-267593D01*
X472302Y-270926D01*
X472932Y-274259D01*
X474192Y-276760D01*
X476082Y-278426D01*
X478287Y-279259D01*
X480492Y-278842D01*
X482382Y-277593D01*
X483642Y-275926D01*
G01X523322Y-258959D02*
Y-266959D01*
X527322D01*
G01X535122D02*
Y-261626D01*
G01Y-262559D02*
X534722Y-262026D01*
X534122Y-261759D01*
X533422Y-261626D01*
X532722Y-261892D01*
X532122Y-262426D01*
X531722Y-263226D01*
X531522Y-264292D01*
X531722Y-265359D01*
X532122Y-266159D01*
X532722Y-266692D01*
X533422Y-266959D01*
X534122Y-266826D01*
X534722Y-266426D01*
X535122Y-265893D01*
G01X539222Y-269359D02*
X539822Y-269626D01*
X540622Y-269359D01*
X541122Y-268826D01*
X541522Y-268159D01*
X542122Y-266026D01*
X543422Y-261626D01*
G01X540222D02*
X542122Y-266026D01*
G01X547822Y-263359D02*
X551022D01*
X550722Y-262426D01*
X550222Y-261892D01*
X549522Y-261626D01*
X548822Y-261759D01*
X548222Y-262159D01*
X547822Y-263092D01*
X547622Y-263893D01*
Y-264692D01*
X547822Y-265492D01*
X548322Y-266292D01*
X548922Y-266826D01*
X549622Y-266959D01*
X550322Y-266692D01*
X551022Y-265893D01*
G01X555922Y-266959D02*
Y-261626D01*
G01Y-262692D02*
X556422Y-262159D01*
X556922Y-261759D01*
X557622Y-261626D01*
X558122Y-261759D01*
X558722Y-262159D01*
G01X542022Y-316959D02*
Y-308959D01*
X546622Y-316959D01*
Y-308959D01*
G01X552322Y-311626D02*
Y-316959D01*
G01Y-309492D02*
X552122Y-309359D01*
Y-309092D01*
X552322Y-308959D01*
X552522Y-309092D01*
Y-309359D01*
X552322Y-309492D01*
G01X558622Y-316959D02*
Y-311626D01*
G01Y-312959D02*
X559022Y-312292D01*
X559622Y-311759D01*
X560422Y-311626D01*
X561122Y-311759D01*
X561722Y-312292D01*
X562022Y-313226D01*
Y-316959D01*
G01X570122D02*
Y-311626D01*
G01Y-312559D02*
X569722Y-312026D01*
X569122Y-311759D01*
X568422Y-311626D01*
X567722Y-311892D01*
X567122Y-312426D01*
X566722Y-313226D01*
X566522Y-314292D01*
X566722Y-315359D01*
X567122Y-316159D01*
X567722Y-316692D01*
X568422Y-316959D01*
X569122Y-316826D01*
X569722Y-316426D01*
X570122Y-315893D01*
G01X547622Y-287692D02*
X548022Y-287292D01*
X548322Y-286626D01*
X548522Y-285692D01*
X548322Y-284892D01*
X547922Y-284359D01*
X547222Y-283959D01*
X544522D01*
Y-291959D01*
X547822D01*
X548522Y-291426D01*
X548922Y-290626D01*
X549122Y-289692D01*
X548922Y-288759D01*
X548322Y-287959D01*
X547622Y-287692D01*
X544522D01*
G01X554822Y-291959D02*
X554022Y-291826D01*
X553322Y-291292D01*
X552722Y-290492D01*
X552322Y-289559D01*
X552122Y-288492D01*
Y-287426D01*
X552322Y-286359D01*
X552722Y-285426D01*
X553322Y-284626D01*
X554022Y-284092D01*
X554822Y-283959D01*
X555622Y-284092D01*
X556322Y-284626D01*
X556922Y-285426D01*
X557322Y-286359D01*
X557522Y-287426D01*
Y-288492D01*
X557322Y-289559D01*
X556922Y-290492D01*
X556322Y-291292D01*
X555622Y-291826D01*
X554822Y-291959D01*
G01X562822Y-283959D02*
Y-291959D01*
G01X560522Y-283959D02*
X565122D01*
G01X570822D02*
Y-291959D01*
G01X568522Y-283959D02*
X573122D01*
G01X578822Y-291959D02*
X578022Y-291826D01*
X577322Y-291292D01*
X576722Y-290492D01*
X576322Y-289559D01*
X576122Y-288492D01*
Y-287426D01*
X576322Y-286359D01*
X576722Y-285426D01*
X577322Y-284626D01*
X578022Y-284092D01*
X578822Y-283959D01*
X579622Y-284092D01*
X580322Y-284626D01*
X580922Y-285426D01*
X581322Y-286359D01*
X581522Y-287426D01*
Y-288492D01*
X581322Y-289559D01*
X580922Y-290492D01*
X580322Y-291292D01*
X579622Y-291826D01*
X578822Y-291959D01*
G01X584222D02*
Y-283959D01*
X586822Y-290626D01*
X589422Y-283959D01*
Y-291959D01*
G01X574922Y-263626D02*
X575622Y-262692D01*
X576222Y-262159D01*
X577022Y-261892D01*
X577722Y-262159D01*
X578222Y-262692D01*
X578622Y-263492D01*
X578722Y-264426D01*
X578622Y-265226D01*
X578222Y-266026D01*
X577622Y-266692D01*
X576922Y-266959D01*
X576122Y-266692D01*
X575422Y-265893D01*
X575022Y-264692D01*
X574922Y-263359D01*
X575122Y-261626D01*
X575422Y-260692D01*
X575922Y-259759D01*
X576622Y-259092D01*
X577322Y-258959D01*
X578022Y-259226D01*
X578522Y-259892D01*
G01X649922Y-310292D02*
X650522Y-309492D01*
X651222Y-309092D01*
X652022Y-308959D01*
X653022Y-309226D01*
X653722Y-309892D01*
X653922Y-310692D01*
X653822Y-311493D01*
X653422Y-312159D01*
X651422Y-313492D01*
X650522Y-314426D01*
X649922Y-315759D01*
X649722Y-316959D01*
X653922D01*
G01X659822Y-308959D02*
X659022Y-309226D01*
X658422Y-309892D01*
X658022Y-310692D01*
X657722Y-311759D01*
X657622Y-312959D01*
X657722Y-314159D01*
X658022Y-315226D01*
X658422Y-316026D01*
X659022Y-316692D01*
X659822Y-316959D01*
X660622Y-316692D01*
X661222Y-316026D01*
X661622Y-315226D01*
X661922Y-314159D01*
X662022Y-312959D01*
X661922Y-311759D01*
X661622Y-310692D01*
X661222Y-309892D01*
X660622Y-309226D01*
X659822Y-308959D01*
G01X665922Y-310292D02*
X666522Y-309492D01*
X667222Y-309092D01*
X668022Y-308959D01*
X669022Y-309226D01*
X669722Y-309892D01*
X669922Y-310692D01*
X669822Y-311493D01*
X669422Y-312159D01*
X667422Y-313492D01*
X666522Y-314426D01*
X665922Y-315759D01*
X665722Y-316959D01*
X669922D01*
G01X673922Y-310292D02*
X674522Y-309492D01*
X675222Y-309092D01*
X676022Y-308959D01*
X677022Y-309226D01*
X677722Y-309892D01*
X677922Y-310692D01*
X677822Y-311493D01*
X677422Y-312159D01*
X675422Y-313492D01*
X674522Y-314426D01*
X673922Y-315759D01*
X673722Y-316959D01*
X677922D01*
G01X682022Y-317226D02*
X685622Y-308959D01*
G01X691822Y-316959D02*
Y-308959D01*
X690622Y-310559D01*
G01Y-316959D02*
X693022D01*
G01X697922Y-310292D02*
X698522Y-309492D01*
X699222Y-309092D01*
X700022Y-308959D01*
X701022Y-309226D01*
X701722Y-309892D01*
X701922Y-310692D01*
X701822Y-311493D01*
X701422Y-312159D01*
X699422Y-313492D01*
X698522Y-314426D01*
X697922Y-315759D01*
X697722Y-316959D01*
X701922D01*
G01X706022Y-317226D02*
X709622Y-308959D01*
G01X715822D02*
X715022Y-309226D01*
X714422Y-309892D01*
X714022Y-310692D01*
X713722Y-311759D01*
X713622Y-312959D01*
X713722Y-314159D01*
X714022Y-315226D01*
X714422Y-316026D01*
X715022Y-316692D01*
X715822Y-316959D01*
X716622Y-316692D01*
X717222Y-316026D01*
X717622Y-315226D01*
X717922Y-314159D01*
X718022Y-312959D01*
X717922Y-311759D01*
X717622Y-310692D01*
X717222Y-309892D01*
X716622Y-309226D01*
X715822Y-308959D01*
G01X722122Y-316026D02*
X722822Y-316692D01*
X723622Y-316959D01*
X724422Y-316692D01*
X725122Y-315893D01*
X725622Y-314692D01*
X725822Y-313492D01*
Y-312026D01*
X725622Y-310826D01*
X725122Y-309759D01*
X724522Y-309226D01*
X723822Y-308959D01*
X723022Y-309226D01*
X722422Y-309759D01*
X722022Y-310559D01*
X721822Y-311626D01*
X722022Y-312559D01*
X722522Y-313492D01*
X723122Y-314026D01*
X723822Y-314159D01*
X724622Y-313893D01*
X725222Y-313226D01*
X725822Y-312026D01*
G01X649622Y-291959D02*
Y-283959D01*
X651622D01*
X652422Y-284359D01*
X653022Y-284892D01*
X653522Y-285692D01*
X653922Y-286626D01*
X654022Y-287959D01*
X653922Y-289292D01*
X653522Y-290226D01*
X653022Y-291026D01*
X652422Y-291559D01*
X651622Y-291959D01*
X649622D01*
G01X657322D02*
X659822Y-283959D01*
X662322Y-291959D01*
G01X661422Y-289159D02*
X658222D01*
G01X667822Y-283959D02*
X667022Y-284226D01*
X666422Y-284892D01*
X666022Y-285692D01*
X665722Y-286759D01*
X665622Y-287959D01*
X665722Y-289159D01*
X666022Y-290226D01*
X666422Y-291026D01*
X667022Y-291692D01*
X667822Y-291959D01*
X668622Y-291692D01*
X669222Y-291026D01*
X669622Y-290226D01*
X669922Y-289159D01*
X670022Y-287959D01*
X669922Y-286759D01*
X669622Y-285692D01*
X669222Y-284892D01*
X668622Y-284226D01*
X667822Y-283959D01*
G01X673922Y-291959D02*
Y-283959D01*
X677722D01*
G01X676322Y-287826D02*
X673922D01*
G01X683822Y-283959D02*
X683022Y-284226D01*
X682422Y-284892D01*
X682022Y-285692D01*
X681722Y-286759D01*
X681622Y-287959D01*
X681722Y-289159D01*
X682022Y-290226D01*
X682422Y-291026D01*
X683022Y-291692D01*
X683822Y-291959D01*
X684622Y-291692D01*
X685222Y-291026D01*
X685622Y-290226D01*
X685922Y-289159D01*
X686022Y-287959D01*
X685922Y-286759D01*
X685622Y-285692D01*
X685222Y-284892D01*
X684622Y-284226D01*
X683822Y-283959D01*
G01X691822D02*
Y-291959D01*
G01X689522Y-283959D02*
X694122D01*
G01X697922Y-291959D02*
Y-283959D01*
X701722D01*
G01X700322Y-287826D02*
X697922D01*
G01X708622Y-287692D02*
X709022Y-287292D01*
X709322Y-286626D01*
X709522Y-285692D01*
X709322Y-284892D01*
X708922Y-284359D01*
X708222Y-283959D01*
X705522D01*
Y-291959D01*
X708822D01*
X709522Y-291426D01*
X709922Y-290626D01*
X710122Y-289692D01*
X709922Y-288759D01*
X709322Y-287959D01*
X708622Y-287692D01*
X705522D01*
G01X713922Y-288626D02*
X714622Y-287692D01*
X715222Y-287159D01*
X716022Y-286892D01*
X716722Y-287159D01*
X717222Y-287692D01*
X717622Y-288492D01*
X717722Y-289426D01*
X717622Y-290226D01*
X717222Y-291026D01*
X716622Y-291692D01*
X715922Y-291959D01*
X715122Y-291692D01*
X714422Y-290893D01*
X714022Y-289692D01*
X713922Y-288359D01*
X714122Y-286626D01*
X714422Y-285692D01*
X714922Y-284759D01*
X715622Y-284092D01*
X716322Y-283959D01*
X717022Y-284226D01*
X717522Y-284892D01*
G01X721622Y-291959D02*
Y-283959D01*
X723622D01*
X724422Y-284359D01*
X725022Y-284892D01*
X725522Y-285692D01*
X725922Y-286626D01*
X726022Y-287959D01*
X725922Y-289292D01*
X725522Y-290226D01*
X725022Y-291026D01*
X724422Y-291559D01*
X723622Y-291959D01*
X721622D01*
G01X731822Y-283959D02*
X731022Y-284226D01*
X730422Y-284892D01*
X730022Y-285692D01*
X729722Y-286759D01*
X729622Y-287959D01*
X729722Y-289159D01*
X730022Y-290226D01*
X730422Y-291026D01*
X731022Y-291692D01*
X731822Y-291959D01*
X732622Y-291692D01*
X733222Y-291026D01*
X733622Y-290226D01*
X733922Y-289159D01*
X734022Y-287959D01*
X733922Y-286759D01*
X733622Y-285692D01*
X733222Y-284892D01*
X732622Y-284226D01*
X731822Y-283959D01*
G01X649862Y-270000D02*
Y-263700D01*
X652838D01*
G01X651742Y-266745D02*
X649862D01*
G01X657650Y-263700D02*
X657023Y-263910D01*
X656553Y-264435D01*
X656240Y-265065D01*
X656005Y-265905D01*
X655927Y-266850D01*
X656005Y-267795D01*
X656240Y-268635D01*
X656553Y-269265D01*
X657023Y-269790D01*
X657650Y-270000D01*
X658277Y-269790D01*
X658747Y-269265D01*
X659060Y-268635D01*
X659295Y-267795D01*
X659373Y-266850D01*
X659295Y-265905D01*
X659060Y-265065D01*
X658747Y-264435D01*
X658277Y-263910D01*
X657650Y-263700D01*
G01X663950D02*
Y-270000D01*
G01X662148Y-263700D02*
X665752D01*
G01X667900Y-272100D02*
X672600D01*
G01X674983Y-270000D02*
Y-263700D01*
X676863D01*
X677490Y-264015D01*
X677960Y-264750D01*
X678117Y-265590D01*
X677960Y-266430D01*
X677568Y-267060D01*
X676863Y-267375D01*
X674983D01*
G01X684573Y-264225D02*
X684103Y-263910D01*
X683555Y-263700D01*
X682928D01*
X682223Y-264015D01*
X681675Y-264540D01*
X681283Y-265170D01*
X680970Y-266220D01*
X680892Y-267165D01*
X681048Y-268110D01*
X681283Y-268740D01*
X681753Y-269370D01*
X682302Y-269790D01*
X682850Y-270000D01*
X683398D01*
X683947Y-269790D01*
X684417Y-269475D01*
X684808Y-269055D01*
G01X689777Y-266640D02*
X690090Y-266325D01*
X690325Y-265800D01*
X690482Y-265065D01*
X690325Y-264435D01*
X690012Y-264015D01*
X689463Y-263700D01*
X687348D01*
Y-270000D01*
X689933D01*
X690482Y-269580D01*
X690795Y-268950D01*
X690952Y-268215D01*
X690795Y-267480D01*
X690325Y-266850D01*
X689777Y-266640D01*
X687348D01*
G01X693100Y-272100D02*
X697800D01*
G01X700262Y-270000D02*
Y-263700D01*
X703238D01*
G01X702142Y-266745D02*
X700262D01*
G01X706092Y-270000D02*
X708050Y-263700D01*
X710008Y-270000D01*
G01X709303Y-267795D02*
X706797D01*
G01X712548Y-270000D02*
Y-263700D01*
X716152Y-270000D01*
Y-263700D01*
G01X718300Y-272100D02*
X723000D01*
G01X727577Y-266640D02*
X727890Y-266325D01*
X728125Y-265800D01*
X728282Y-265065D01*
X728125Y-264435D01*
X727812Y-264015D01*
X727263Y-263700D01*
X725148D01*
Y-270000D01*
X727733D01*
X728282Y-269580D01*
X728595Y-268950D01*
X728752Y-268215D01*
X728595Y-267480D01*
X728125Y-266850D01*
X727577Y-266640D01*
X725148D01*
G01X733250Y-270000D02*
X732623Y-269895D01*
X732075Y-269475D01*
X731605Y-268845D01*
X731292Y-268110D01*
X731135Y-267270D01*
Y-266430D01*
X731292Y-265590D01*
X731605Y-264855D01*
X732075Y-264225D01*
X732623Y-263805D01*
X733250Y-263700D01*
X733877Y-263805D01*
X734425Y-264225D01*
X734895Y-264855D01*
X735208Y-265590D01*
X735365Y-266430D01*
Y-267270D01*
X735208Y-268110D01*
X734895Y-268845D01*
X734425Y-269475D01*
X733877Y-269895D01*
X733250Y-270000D01*
G01X737592D02*
X739550Y-263700D01*
X741508Y-270000D01*
G01X740803Y-267795D02*
X738297D01*
G01X744283Y-270000D02*
Y-263700D01*
X746242D01*
X746868Y-264015D01*
X747260Y-264435D01*
X747417Y-265275D01*
X747260Y-266115D01*
X746790Y-266640D01*
X746242Y-266955D01*
X744283D01*
G01X746242D02*
X747417Y-270000D01*
G01X750427D02*
Y-263700D01*
X751993D01*
X752620Y-264015D01*
X753090Y-264435D01*
X753482Y-265065D01*
X753795Y-265800D01*
X753873Y-266850D01*
X753795Y-267900D01*
X753482Y-268635D01*
X753090Y-269265D01*
X752620Y-269685D01*
X751993Y-270000D01*
X750427D01*
G01X756100Y-272100D02*
X760800D01*
G01X762713Y-270000D02*
Y-263700D01*
X764750Y-268950D01*
X766787Y-263700D01*
Y-270000D01*
G01X769483D02*
Y-263700D01*
X771363D01*
X771990Y-264015D01*
X772460Y-264750D01*
X772617Y-265590D01*
X772460Y-266430D01*
X772068Y-267060D01*
X771363Y-267375D01*
X769483D01*
G01X775627Y-269055D02*
X776097Y-269580D01*
X776645Y-269895D01*
X777350Y-270000D01*
X778055Y-269790D01*
X778603Y-269370D01*
X778995Y-268635D01*
X779073Y-267795D01*
X778917Y-266955D01*
X778525Y-266430D01*
X777977Y-266010D01*
X777428Y-265905D01*
X776880Y-266010D01*
X776175Y-266430D01*
X776410Y-263700D01*
X778525D01*
G01X783650D02*
X783023Y-263910D01*
X782553Y-264435D01*
X782240Y-265065D01*
X782005Y-265905D01*
X781927Y-266850D01*
X782005Y-267795D01*
X782240Y-268635D01*
X782553Y-269265D01*
X783023Y-269790D01*
X783650Y-270000D01*
X784277Y-269790D01*
X784747Y-269265D01*
X785060Y-268635D01*
X785295Y-267795D01*
X785373Y-266850D01*
X785295Y-265905D01*
X785060Y-265065D01*
X784747Y-264435D01*
X784277Y-263910D01*
X783650Y-263700D01*
G01X790890Y-270000D02*
Y-263700D01*
X787992Y-268215D01*
X791908D01*
G01X796250Y-270000D02*
X796798Y-269895D01*
X797425Y-269580D01*
X797817Y-269055D01*
X797973Y-268320D01*
X797817Y-267585D01*
X797347Y-266955D01*
X796642Y-266640D01*
X795858D01*
X795388Y-266430D01*
X794997Y-265905D01*
X794840Y-265170D01*
X795075Y-264435D01*
X795623Y-263910D01*
X796250Y-263700D01*
X796877Y-263910D01*
X797425Y-264435D01*
X797660Y-265170D01*
X797503Y-265905D01*
X797112Y-266430D01*
X796642Y-266640D01*
X795858D01*
X795153Y-266955D01*
X794683Y-267585D01*
X794527Y-268320D01*
X794683Y-269055D01*
X795075Y-269580D01*
X795702Y-269895D01*
X796250Y-270000D01*
G01X738322Y-319959D02*
Y-311959D01*
X737122Y-313559D01*
G01Y-319959D02*
X739522D01*
G01X744422Y-316626D02*
X745122Y-315692D01*
X745722Y-315159D01*
X746522Y-314892D01*
X747222Y-315159D01*
X747722Y-315692D01*
X748122Y-316492D01*
X748222Y-317426D01*
X748122Y-318226D01*
X747722Y-319026D01*
X747122Y-319692D01*
X746422Y-319959D01*
X745622Y-319692D01*
X744922Y-318893D01*
X744522Y-317692D01*
X744422Y-316359D01*
X744622Y-314626D01*
X744922Y-313692D01*
X745422Y-312759D01*
X746122Y-312092D01*
X746822Y-311959D01*
X747522Y-312226D01*
X748022Y-312892D01*
G01X754322Y-320226D02*
X754122Y-320092D01*
Y-319826D01*
X754322Y-319692D01*
X754522Y-319826D01*
Y-320092D01*
X754322Y-320226D01*
G01X760422Y-316626D02*
X761122Y-315692D01*
X761722Y-315159D01*
X762522Y-314892D01*
X763222Y-315159D01*
X763722Y-315692D01*
X764122Y-316492D01*
X764222Y-317426D01*
X764122Y-318226D01*
X763722Y-319026D01*
X763122Y-319692D01*
X762422Y-319959D01*
X761622Y-319692D01*
X760922Y-318893D01*
X760522Y-317692D01*
X760422Y-316359D01*
X760622Y-314626D01*
X760922Y-313692D01*
X761422Y-312759D01*
X762122Y-312092D01*
X762822Y-311959D01*
X763522Y-312226D01*
X764022Y-312892D01*
G01X783322Y-319959D02*
Y-311959D01*
X782122Y-313559D01*
G01Y-319959D02*
X784522D01*
G01X791122D02*
X791322Y-318226D01*
X791622Y-316759D01*
X792022Y-315426D01*
X792522Y-313959D01*
X793322Y-311959D01*
X789322D01*
G01X799322Y-320226D02*
X799122Y-320092D01*
Y-319826D01*
X799322Y-319692D01*
X799522Y-319826D01*
Y-320092D01*
X799322Y-320226D01*
G01X805422Y-313292D02*
X806022Y-312492D01*
X806722Y-312092D01*
X807522Y-311959D01*
X808522Y-312226D01*
X809222Y-312892D01*
X809422Y-313692D01*
X809322Y-314493D01*
X808922Y-315159D01*
X806922Y-316492D01*
X806022Y-317426D01*
X805422Y-318759D01*
X805222Y-319959D01*
X809422D01*
G01X803122Y-294959D02*
Y-286959D01*
X805122D01*
X805922Y-287359D01*
X806522Y-287892D01*
X807022Y-288692D01*
X807422Y-289626D01*
X807522Y-290959D01*
X807422Y-292292D01*
X807022Y-293226D01*
X806522Y-294026D01*
X805922Y-294559D01*
X805122Y-294959D01*
X803122D01*
G54D49*
X101772Y1243747D03*
G54D59*
G01X24016Y241516D02*
Y245026D01*
X24370Y246808D01*
X24791Y247824D01*
X25545Y248578D01*
G01X25500Y977500D02*
X25019Y975086D01*
X24016Y972662D01*
Y968288D01*
G01X54926Y296651D02*
X54928Y299263D01*
X55336Y300246D01*
Y304940D01*
G01X55836Y1031712D02*
Y1025836D01*
X53000Y1023000D01*
Y1021500D01*
G01X147707Y241516D02*
Y245095D01*
X148482Y246967D01*
Y249482D01*
X149000Y250000D01*
G01X164296Y297723D02*
X164633Y298537D01*
Y304940D01*
G01X151000Y981000D02*
X149123Y979122D01*
X147707Y975698D01*
Y971437D01*
G01X164633Y1031712D02*
Y1027307D01*
X163097Y1023597D01*
X162500Y1023000D01*
M02*
